FILE_TYPE = MACRO_DRAWING;
SET COLOR_WIRE YELLOW;
SET COLOR_PROP MONO;
SET COLOR_DOT WHITE;
SET COLOR_ARC YELLOW;
SET COLOR_BODY GREEN;
SET COLOR_NOTE MONO;
SET PROP_DISPLAY VALUE;
SET PAGE_NUMBER P49;
FORCEADD OFFPAGE..3
(1650 5250);
FORCEPROP 2 LAST $XR0 26 
J 0
(1864 5250);
DISPLAY 0.638298 (1864 5250);
PAINT MONO (1864 5250);
FORCEPROP 2 LAST $XR1 50 
J 0
(1954 5250);
DISPLAY 0.638298 (1954 5250);
PAINT MONO (1954 5250);
FORCEPROP 2 LAST CDS_LIB mstr_standard
J 0
(1650 5250);
DISPLAY 0.787234 (1650 5250);
PAINT MONO (1650 5250);
DISPLAY INVISIBLE (1650 5250);
FORCEPROP 1 LAST OFFPAGE TRUE
J 0
(1975 5125);
DISPLAY 0.936170 (1975 5125);
PAINT GREEN (1975 5125);
DISPLAY INVISIBLE (1975 5125);
FORCEPROP 1 LAST COMMENT_BODY TRUE
J 0
(1600 5150);
DISPLAY 0.936170 (1600 5150);
PAINT GREEN (1600 5150);
DISPLAY INVISIBLE (1600 5150);
FORCEPROP 2 LAST PATH I1
J 0
(1850 5325);
DISPLAY 0.787234 (1850 5325);
PAINT MONO (1850 5325);
DISPLAY INVISIBLE (1850 5325);
FORCEADD TAP..6
R 2
(650 5100);
FORCEPROP 3 LASTPIN (600 5100) SIG_NAME M_D_DQS_DP<16>
J 0
(610 5110);
DISPLAY 0.659574 (610 5110);
PAINT MONO (610 5110);
DISPLAY INVISIBLE (610 5110);
FORCEPROP 1 LASTPIN (600 5100) BN 16
J 2
(650 5110);
DISPLAY 0.617021 (650 5110);
PAINT PINK (650 5110);
FORCEPROP 2 LAST CDS_LIB mstr_standard
J 0
(650 5100);
DISPLAY 0.787234 (650 5100);
PAINT MONO (650 5100);
DISPLAY INVISIBLE (650 5100);
FORCEPROP 1 LAST BODY_TYPE PLUMBING
J 2
(650 5050);
DISPLAY 1.234043 (650 5050);
PAINT GREEN (650 5050);
DISPLAY INVISIBLE (650 5050);
FORCEPROP 1 LAST HDL_TAP TRUE
J 2
(325 4975);
DISPLAY 1.234043 (325 4975);
PAINT GREEN (325 4975);
DISPLAY INVISIBLE (325 4975);
FORCEPROP 1 LAST PATH I10
J 2
(650 5100);
DISPLAY 0.936170 (650 5100);
PAINT GREEN (650 5100);
DISPLAY INVISIBLE (650 5100);
FORCEADD TAP..6
R 2
(-1750 2500);
FORCEPROP 3 LASTPIN (-1800 2500) SIG_NAME M_D_DQ<11>
J 0
(-1790 2510);
DISPLAY 0.659574 (-1790 2510);
PAINT MONO (-1790 2510);
DISPLAY INVISIBLE (-1790 2510);
FORCEPROP 1 LASTPIN (-1800 2500) BN 11
J 2
(-1750 2510);
DISPLAY 0.617021 (-1750 2510);
PAINT PINK (-1750 2510);
FORCEPROP 2 LAST CDS_LIB mstr_standard
J 2
(-1750 2500);
DISPLAY 0.787234 (-1750 2500);
PAINT MONO (-1750 2500);
DISPLAY INVISIBLE (-1750 2500);
FORCEPROP 1 LAST BODY_TYPE PLUMBING
J 2
(-1750 2450);
DISPLAY 1.234043 (-1750 2450);
PAINT GREEN (-1750 2450);
DISPLAY INVISIBLE (-1750 2450);
FORCEPROP 1 LAST HDL_TAP TRUE
J 2
(-2075 2375);
DISPLAY 1.234043 (-2075 2375);
PAINT GREEN (-2075 2375);
DISPLAY INVISIBLE (-2075 2375);
FORCEPROP 1 LAST PATH I100
J 2
(-1750 2500);
DISPLAY 0.936170 (-1750 2500);
PAINT GREEN (-1750 2500);
DISPLAY INVISIBLE (-1750 2500);
FORCEADD TAP..6
R 2
(-1750 2450);
FORCEPROP 3 LASTPIN (-1800 2450) SIG_NAME M_D_DQ<8>
J 0
(-1790 2460);
DISPLAY 0.659574 (-1790 2460);
PAINT MONO (-1790 2460);
DISPLAY INVISIBLE (-1790 2460);
FORCEPROP 1 LASTPIN (-1800 2450) BN 8
J 2
(-1750 2460);
DISPLAY 0.617021 (-1750 2460);
PAINT PINK (-1750 2460);
FORCEPROP 2 LAST CDS_LIB mstr_standard
J 2
(-1750 2450);
DISPLAY 0.787234 (-1750 2450);
PAINT MONO (-1750 2450);
DISPLAY INVISIBLE (-1750 2450);
FORCEPROP 1 LAST BODY_TYPE PLUMBING
J 2
(-1750 2400);
DISPLAY 1.234043 (-1750 2400);
PAINT GREEN (-1750 2400);
DISPLAY INVISIBLE (-1750 2400);
FORCEPROP 1 LAST HDL_TAP TRUE
J 2
(-2075 2325);
DISPLAY 1.234043 (-2075 2325);
PAINT GREEN (-2075 2325);
DISPLAY INVISIBLE (-2075 2325);
FORCEPROP 1 LAST PATH I101
J 2
(-1750 2450);
DISPLAY 0.936170 (-1750 2450);
PAINT GREEN (-1750 2450);
DISPLAY INVISIBLE (-1750 2450);
FORCEADD TAP..6
R 2
(-1750 2350);
FORCEPROP 3 LASTPIN (-1800 2350) SIG_NAME M_D_DQ<6>
J 0
(-1790 2360);
DISPLAY 0.659574 (-1790 2360);
PAINT MONO (-1790 2360);
DISPLAY INVISIBLE (-1790 2360);
FORCEPROP 1 LASTPIN (-1800 2350) BN 6
J 2
(-1750 2360);
DISPLAY 0.617021 (-1750 2360);
PAINT PINK (-1750 2360);
FORCEPROP 2 LAST CDS_LIB mstr_standard
J 2
(-1750 2350);
DISPLAY 0.787234 (-1750 2350);
PAINT MONO (-1750 2350);
DISPLAY INVISIBLE (-1750 2350);
FORCEPROP 1 LAST BODY_TYPE PLUMBING
J 2
(-1750 2300);
DISPLAY 1.234043 (-1750 2300);
PAINT GREEN (-1750 2300);
DISPLAY INVISIBLE (-1750 2300);
FORCEPROP 1 LAST HDL_TAP TRUE
J 2
(-2075 2225);
DISPLAY 1.234043 (-2075 2225);
PAINT GREEN (-2075 2225);
DISPLAY INVISIBLE (-2075 2225);
FORCEPROP 1 LAST PATH I102
J 2
(-1750 2350);
DISPLAY 0.936170 (-1750 2350);
PAINT GREEN (-1750 2350);
DISPLAY INVISIBLE (-1750 2350);
FORCEADD TAP..6
R 2
(-1750 2400);
FORCEPROP 3 LASTPIN (-1800 2400) SIG_NAME M_D_DQ<9>
J 0
(-1790 2410);
DISPLAY 0.659574 (-1790 2410);
PAINT MONO (-1790 2410);
DISPLAY INVISIBLE (-1790 2410);
FORCEPROP 1 LASTPIN (-1800 2400) BN 9
J 2
(-1750 2410);
DISPLAY 0.617021 (-1750 2410);
PAINT PINK (-1750 2410);
FORCEPROP 2 LAST CDS_LIB mstr_standard
J 2
(-1750 2400);
DISPLAY 0.787234 (-1750 2400);
PAINT MONO (-1750 2400);
DISPLAY INVISIBLE (-1750 2400);
FORCEPROP 1 LAST BODY_TYPE PLUMBING
J 2
(-1750 2350);
DISPLAY 1.234043 (-1750 2350);
PAINT GREEN (-1750 2350);
DISPLAY INVISIBLE (-1750 2350);
FORCEPROP 1 LAST HDL_TAP TRUE
J 2
(-2075 2275);
DISPLAY 1.234043 (-2075 2275);
PAINT GREEN (-2075 2275);
DISPLAY INVISIBLE (-2075 2275);
FORCEPROP 1 LAST PATH I103
J 2
(-1750 2400);
DISPLAY 0.936170 (-1750 2400);
PAINT GREEN (-1750 2400);
DISPLAY INVISIBLE (-1750 2400);
FORCEADD TAP..6
R 2
(-1750 2300);
FORCEPROP 3 LASTPIN (-1800 2300) SIG_NAME M_D_DQ<7>
J 0
(-1790 2310);
DISPLAY 0.659574 (-1790 2310);
PAINT MONO (-1790 2310);
DISPLAY INVISIBLE (-1790 2310);
FORCEPROP 1 LASTPIN (-1800 2300) BN 7
J 2
(-1750 2310);
DISPLAY 0.617021 (-1750 2310);
PAINT PINK (-1750 2310);
FORCEPROP 2 LAST CDS_LIB mstr_standard
J 2
(-1750 2300);
DISPLAY 0.787234 (-1750 2300);
PAINT MONO (-1750 2300);
DISPLAY INVISIBLE (-1750 2300);
FORCEPROP 1 LAST BODY_TYPE PLUMBING
J 2
(-1750 2250);
DISPLAY 1.234043 (-1750 2250);
PAINT GREEN (-1750 2250);
DISPLAY INVISIBLE (-1750 2250);
FORCEPROP 1 LAST HDL_TAP TRUE
J 2
(-2075 2175);
DISPLAY 1.234043 (-2075 2175);
PAINT GREEN (-2075 2175);
DISPLAY INVISIBLE (-2075 2175);
FORCEPROP 1 LAST PATH I104
J 2
(-1750 2300);
DISPLAY 0.936170 (-1750 2300);
PAINT GREEN (-1750 2300);
DISPLAY INVISIBLE (-1750 2300);
FORCEADD TAP..6
R 2
(-1750 2250);
FORCEPROP 3 LASTPIN (-1800 2250) SIG_NAME M_D_DQ<4>
J 0
(-1790 2260);
DISPLAY 0.659574 (-1790 2260);
PAINT MONO (-1790 2260);
DISPLAY INVISIBLE (-1790 2260);
FORCEPROP 1 LASTPIN (-1800 2250) BN 4
J 2
(-1750 2260);
DISPLAY 0.617021 (-1750 2260);
PAINT PINK (-1750 2260);
FORCEPROP 2 LAST CDS_LIB mstr_standard
J 2
(-1750 2250);
DISPLAY 0.787234 (-1750 2250);
PAINT MONO (-1750 2250);
DISPLAY INVISIBLE (-1750 2250);
FORCEPROP 1 LAST BODY_TYPE PLUMBING
J 2
(-1750 2200);
DISPLAY 1.234043 (-1750 2200);
PAINT GREEN (-1750 2200);
DISPLAY INVISIBLE (-1750 2200);
FORCEPROP 1 LAST HDL_TAP TRUE
J 2
(-2075 2125);
DISPLAY 1.234043 (-2075 2125);
PAINT GREEN (-2075 2125);
DISPLAY INVISIBLE (-2075 2125);
FORCEPROP 1 LAST PATH I105
J 2
(-1750 2250);
DISPLAY 0.936170 (-1750 2250);
PAINT GREEN (-1750 2250);
DISPLAY INVISIBLE (-1750 2250);
FORCEADD TAP..6
R 2
(-1750 2150);
FORCEPROP 3 LASTPIN (-1800 2150) SIG_NAME M_D_DQ<2>
J 0
(-1790 2160);
DISPLAY 0.659574 (-1790 2160);
PAINT MONO (-1790 2160);
DISPLAY INVISIBLE (-1790 2160);
FORCEPROP 1 LASTPIN (-1800 2150) BN 2
J 2
(-1750 2160);
DISPLAY 0.617021 (-1750 2160);
PAINT PINK (-1750 2160);
FORCEPROP 2 LAST CDS_LIB mstr_standard
J 2
(-1750 2150);
DISPLAY 0.787234 (-1750 2150);
PAINT MONO (-1750 2150);
DISPLAY INVISIBLE (-1750 2150);
FORCEPROP 1 LAST BODY_TYPE PLUMBING
J 2
(-1750 2100);
DISPLAY 1.234043 (-1750 2100);
PAINT GREEN (-1750 2100);
DISPLAY INVISIBLE (-1750 2100);
FORCEPROP 1 LAST HDL_TAP TRUE
J 2
(-2075 2025);
DISPLAY 1.234043 (-2075 2025);
PAINT GREEN (-2075 2025);
DISPLAY INVISIBLE (-2075 2025);
FORCEPROP 1 LAST PATH I106
J 2
(-1750 2150);
DISPLAY 0.936170 (-1750 2150);
PAINT GREEN (-1750 2150);
DISPLAY INVISIBLE (-1750 2150);
FORCEADD TAP..6
R 2
(-1750 2200);
FORCEPROP 3 LASTPIN (-1800 2200) SIG_NAME M_D_DQ<5>
J 0
(-1790 2210);
DISPLAY 0.659574 (-1790 2210);
PAINT MONO (-1790 2210);
DISPLAY INVISIBLE (-1790 2210);
FORCEPROP 1 LASTPIN (-1800 2200) BN 5
J 2
(-1750 2210);
DISPLAY 0.617021 (-1750 2210);
PAINT PINK (-1750 2210);
FORCEPROP 2 LAST CDS_LIB mstr_standard
J 2
(-1750 2200);
DISPLAY 0.787234 (-1750 2200);
PAINT MONO (-1750 2200);
DISPLAY INVISIBLE (-1750 2200);
FORCEPROP 1 LAST BODY_TYPE PLUMBING
J 2
(-1750 2150);
DISPLAY 1.234043 (-1750 2150);
PAINT GREEN (-1750 2150);
DISPLAY INVISIBLE (-1750 2150);
FORCEPROP 1 LAST HDL_TAP TRUE
J 2
(-2075 2075);
DISPLAY 1.234043 (-2075 2075);
PAINT GREEN (-2075 2075);
DISPLAY INVISIBLE (-2075 2075);
FORCEPROP 1 LAST PATH I107
J 2
(-1750 2200);
DISPLAY 0.936170 (-1750 2200);
PAINT GREEN (-1750 2200);
DISPLAY INVISIBLE (-1750 2200);
FORCEADD TAP..6
R 2
(-1750 2050);
FORCEPROP 3 LASTPIN (-1800 2050) SIG_NAME M_D_DQ<0>
J 0
(-1790 2060);
DISPLAY 0.659574 (-1790 2060);
PAINT MONO (-1790 2060);
DISPLAY INVISIBLE (-1790 2060);
FORCEPROP 1 LASTPIN (-1800 2050) BN 0
J 2
(-1750 2060);
DISPLAY 0.617021 (-1750 2060);
PAINT PINK (-1750 2060);
FORCEPROP 2 LAST CDS_LIB mstr_standard
J 2
(-1750 2050);
DISPLAY 0.787234 (-1750 2050);
PAINT MONO (-1750 2050);
DISPLAY INVISIBLE (-1750 2050);
FORCEPROP 1 LAST BODY_TYPE PLUMBING
J 2
(-1750 2000);
DISPLAY 1.234043 (-1750 2000);
PAINT GREEN (-1750 2000);
DISPLAY INVISIBLE (-1750 2000);
FORCEPROP 1 LAST HDL_TAP TRUE
J 2
(-2075 1925);
DISPLAY 1.234043 (-2075 1925);
PAINT GREEN (-2075 1925);
DISPLAY INVISIBLE (-2075 1925);
FORCEPROP 1 LAST PATH I108
J 2
(-1750 2050);
DISPLAY 0.936170 (-1750 2050);
PAINT GREEN (-1750 2050);
DISPLAY INVISIBLE (-1750 2050);
FORCEADD TAP..6
R 2
(-1750 2100);
FORCEPROP 3 LASTPIN (-1800 2100) SIG_NAME M_D_DQ<3>
J 0
(-1790 2110);
DISPLAY 0.659574 (-1790 2110);
PAINT MONO (-1790 2110);
DISPLAY INVISIBLE (-1790 2110);
FORCEPROP 1 LASTPIN (-1800 2100) BN 3
J 2
(-1750 2110);
DISPLAY 0.617021 (-1750 2110);
PAINT PINK (-1750 2110);
FORCEPROP 2 LAST CDS_LIB mstr_standard
J 2
(-1750 2100);
DISPLAY 0.787234 (-1750 2100);
PAINT MONO (-1750 2100);
DISPLAY INVISIBLE (-1750 2100);
FORCEPROP 1 LAST BODY_TYPE PLUMBING
J 2
(-1750 2050);
DISPLAY 1.234043 (-1750 2050);
PAINT GREEN (-1750 2050);
DISPLAY INVISIBLE (-1750 2050);
FORCEPROP 1 LAST HDL_TAP TRUE
J 2
(-2075 1975);
DISPLAY 1.234043 (-2075 1975);
PAINT GREEN (-2075 1975);
DISPLAY INVISIBLE (-2075 1975);
FORCEPROP 1 LAST PATH I109
J 2
(-1750 2100);
DISPLAY 0.936170 (-1750 2100);
PAINT GREEN (-1750 2100);
DISPLAY INVISIBLE (-1750 2100);
FORCEADD TAP..6
R 2
(650 5000);
FORCEPROP 3 LASTPIN (600 5000) SIG_NAME M_D_DQS_DP<15>
J 0
(610 5010);
DISPLAY 0.659574 (610 5010);
PAINT MONO (610 5010);
DISPLAY INVISIBLE (610 5010);
FORCEPROP 1 LASTPIN (600 5000) BN 15
J 2
(650 5010);
DISPLAY 0.617021 (650 5010);
PAINT PINK (650 5010);
FORCEPROP 2 LAST CDS_LIB mstr_standard
J 0
(650 5000);
DISPLAY 0.787234 (650 5000);
PAINT MONO (650 5000);
DISPLAY INVISIBLE (650 5000);
FORCEPROP 1 LAST BODY_TYPE PLUMBING
J 2
(650 4950);
DISPLAY 1.234043 (650 4950);
PAINT GREEN (650 4950);
DISPLAY INVISIBLE (650 4950);
FORCEPROP 1 LAST HDL_TAP TRUE
J 2
(325 4875);
DISPLAY 1.234043 (325 4875);
PAINT GREEN (325 4875);
DISPLAY INVISIBLE (325 4875);
FORCEPROP 1 LAST PATH I11
J 2
(650 5000);
DISPLAY 0.936170 (650 5000);
PAINT GREEN (650 5000);
DISPLAY INVISIBLE (650 5000);
FORCEADD TAP..6
R 2
(-1750 2000);
FORCEPROP 3 LASTPIN (-1800 2000) SIG_NAME M_D_DQ<1>
J 0
(-1790 2010);
DISPLAY 0.659574 (-1790 2010);
PAINT MONO (-1790 2010);
DISPLAY INVISIBLE (-1790 2010);
FORCEPROP 1 LASTPIN (-1800 2000) BN 1
J 2
(-1750 2010);
DISPLAY 0.617021 (-1750 2010);
PAINT PINK (-1750 2010);
FORCEPROP 2 LAST CDS_LIB mstr_standard
J 2
(-1750 2000);
DISPLAY 0.787234 (-1750 2000);
PAINT MONO (-1750 2000);
DISPLAY INVISIBLE (-1750 2000);
FORCEPROP 1 LAST BODY_TYPE PLUMBING
J 2
(-1750 1950);
DISPLAY 1.234043 (-1750 1950);
PAINT GREEN (-1750 1950);
DISPLAY INVISIBLE (-1750 1950);
FORCEPROP 1 LAST HDL_TAP TRUE
J 2
(-2075 1875);
DISPLAY 1.234043 (-2075 1875);
PAINT GREEN (-2075 1875);
DISPLAY INVISIBLE (-2075 1875);
FORCEPROP 1 LAST PATH I110
J 2
(-1750 2000);
DISPLAY 0.936170 (-1750 2000);
PAINT GREEN (-1750 2000);
DISPLAY INVISIBLE (-1750 2000);
FORCEADD SCONN288_H44441004..1
(-2500 3500);
FORCEPROP 1 LAST LOCATION J4B1
J 0
(-2950 5400);
DISPLAY 0.617021 (-2950 5400);
PAINT AQUA (-2950 5400);
FORCEPROP 1 LAST PART_NUMBER H44441-004
J 0
(-2950 1500);
DISPLAY 0.617021 (-2950 1500);
PAINT BLUE (-2950 1500);
FORCEPROP 1 LAST MATERIAL SCONN
J 0
(-2950 5350);
DISPLAY 0.617021 (-2950 5350);
PAINT SKYBLUE (-2950 5350);
FORCEPROP 2 LASTPIN (-3000 2000) $PN 146
J 2
(-3010 2010);
DISPLAY 0.617021 (-3010 2010);
PAINT ORANGE (-3010 2010);
FORCEPROP 2 LASTPIN (-3000 2350) $PN 284
J 2
(-3010 2360);
DISPLAY 0.617021 (-3010 2360);
PAINT ORANGE (-3010 2360);
FORCEPROP 2 LASTPIN (-3000 2150) $PN 285
J 2
(-3010 2160);
DISPLAY 0.617021 (-3010 2160);
PAINT ORANGE (-3010 2160);
FORCEPROP 2 LASTPIN (-3000 2100) $PN 141
J 2
(-3010 2110);
DISPLAY 0.617021 (-3010 2110);
PAINT ORANGE (-3010 2110);
FORCEPROP 2 LASTPIN (-3000 1700) $PN 230
J 2
(-3010 1710);
DISPLAY 0.617021 (-3010 1710);
PAINT ORANGE (-3010 1710);
FORCEPROP 2 LASTPIN (-3000 2300) $PN 238
J 2
(-3010 2310);
DISPLAY 0.617021 (-3010 2310);
PAINT ORANGE (-3010 2310);
FORCEPROP 2 LASTPIN (-3000 2250) $PN 140
J 2
(-3010 2260);
DISPLAY 0.617021 (-3010 2260);
PAINT ORANGE (-3010 2260);
FORCEPROP 2 LASTPIN (-3000 2200) $PN 139
J 2
(-3010 2210);
DISPLAY 0.617021 (-3010 2210);
PAINT ORANGE (-3010 2210);
FORCEPROP 2 LASTPIN (-3000 3650) $PN 237
J 2
(-3010 3660);
DISPLAY 0.617021 (-3010 3660);
PAINT ORANGE (-3010 3660);
FORCEPROP 2 LASTPIN (-3000 3600) $PN 93
J 2
(-3010 3610);
DISPLAY 0.617021 (-3010 3610);
PAINT ORANGE (-3010 3610);
FORCEPROP 2 LASTPIN (-3000 3550) $PN 89
J 2
(-3010 3560);
DISPLAY 0.617021 (-3010 3560);
PAINT ORANGE (-3010 3560);
FORCEPROP 2 LASTPIN (-3000 3500) $PN 84
J 2
(-3010 3510);
DISPLAY 0.617021 (-3010 3510);
PAINT ORANGE (-3010 3510);
FORCEPROP 2 LASTPIN (-3000 1900) $PN 144
J 2
(-3010 1910);
DISPLAY 0.617021 (-3010 1910);
PAINT ORANGE (-3010 1910);
FORCEPROP 2 LASTPIN (-3000 1850) $PN 227
J 2
(-3010 1860);
DISPLAY 0.617021 (-3010 1860);
PAINT ORANGE (-3010 1860);
FORCEPROP 2 LASTPIN (-3000 1800) $PN 205
J 2
(-3010 1810);
DISPLAY 0.617021 (-3010 1810);
PAINT ORANGE (-3010 1810);
FORCEPROP 2 LASTPIN (-3000 2600) $PN 58
J 2
(-3010 2610);
DISPLAY 0.617021 (-3010 2610);
PAINT ORANGE (-3010 2610);
FORCEPROP 2 LASTPIN (-3000 2650) $PN 222
J 2
(-3010 2660);
DISPLAY 0.617021 (-3010 2660);
PAINT ORANGE (-3010 2660);
FORCEPROP 2 LASTPIN (-3000 3250) $PN 91
J 2
(-3010 3260);
DISPLAY 0.617021 (-3010 3260);
PAINT ORANGE (-3010 3260);
FORCEPROP 2 LASTPIN (-3000 3200) $PN 87
J 2
(-3010 3210);
DISPLAY 0.617021 (-3010 3210);
PAINT ORANGE (-3010 3210);
FORCEPROP 2 LASTPIN (-3000 2550) $PN 78
J 2
(-3010 2560);
DISPLAY 0.617021 (-3010 2560);
PAINT ORANGE (-3010 2560);
FORCEPROP 2 LASTPIN (-2000 5150) $PN 280
J 0
(-1990 5160);
DISPLAY 0.617021 (-1990 5160);
PAINT ORANGE (-1990 5160);
FORCEPROP 2 LASTPIN (-2000 5100) $PN 135
J 0
(-1990 5110);
DISPLAY 0.617021 (-1990 5110);
PAINT ORANGE (-1990 5110);
FORCEPROP 2 LASTPIN (-2000 5050) $PN 273
J 0
(-1990 5060);
DISPLAY 0.617021 (-1990 5060);
PAINT ORANGE (-1990 5060);
FORCEPROP 2 LASTPIN (-2000 5000) $PN 128
J 0
(-1990 5010);
DISPLAY 0.617021 (-1990 5010);
PAINT ORANGE (-1990 5010);
FORCEPROP 2 LASTPIN (-2000 4950) $PN 282
J 0
(-1990 4960);
DISPLAY 0.617021 (-1990 4960);
PAINT ORANGE (-1990 4960);
FORCEPROP 2 LASTPIN (-2000 4900) $PN 137
J 0
(-1990 4910);
DISPLAY 0.617021 (-1990 4910);
PAINT ORANGE (-1990 4910);
FORCEPROP 2 LASTPIN (-2000 4850) $PN 275
J 0
(-1990 4860);
DISPLAY 0.617021 (-1990 4860);
PAINT ORANGE (-1990 4860);
FORCEPROP 2 LASTPIN (-2000 4800) $PN 130
J 0
(-1990 4810);
DISPLAY 0.617021 (-1990 4810);
PAINT ORANGE (-1990 4810);
FORCEPROP 2 LASTPIN (-2000 4750) $PN 269
J 0
(-1990 4760);
DISPLAY 0.617021 (-1990 4760);
PAINT ORANGE (-1990 4760);
FORCEPROP 2 LASTPIN (-2000 4700) $PN 124
J 0
(-1990 4710);
DISPLAY 0.617021 (-1990 4710);
PAINT ORANGE (-1990 4710);
FORCEPROP 2 LASTPIN (-2000 4650) $PN 262
J 0
(-1990 4660);
DISPLAY 0.617021 (-1990 4660);
PAINT ORANGE (-1990 4660);
FORCEPROP 2 LASTPIN (-2000 4600) $PN 117
J 0
(-1990 4610);
DISPLAY 0.617021 (-1990 4610);
PAINT ORANGE (-1990 4610);
FORCEPROP 2 LASTPIN (-2000 4550) $PN 271
J 0
(-1990 4560);
DISPLAY 0.617021 (-1990 4560);
PAINT ORANGE (-1990 4560);
FORCEPROP 2 LASTPIN (-2000 4500) $PN 126
J 0
(-1990 4510);
DISPLAY 0.617021 (-1990 4510);
PAINT ORANGE (-1990 4510);
FORCEPROP 2 LASTPIN (-2000 4450) $PN 264
J 0
(-1990 4460);
DISPLAY 0.617021 (-1990 4460);
PAINT ORANGE (-1990 4460);
FORCEPROP 2 LASTPIN (-2000 4400) $PN 119
J 0
(-1990 4410);
DISPLAY 0.617021 (-1990 4410);
PAINT ORANGE (-1990 4410);
FORCEPROP 2 LASTPIN (-2000 4350) $PN 258
J 0
(-1990 4360);
DISPLAY 0.617021 (-1990 4360);
PAINT ORANGE (-1990 4360);
FORCEPROP 2 LASTPIN (-2000 4300) $PN 113
J 0
(-1990 4310);
DISPLAY 0.617021 (-1990 4310);
PAINT ORANGE (-1990 4310);
FORCEPROP 2 LASTPIN (-2000 4250) $PN 251
J 0
(-1990 4260);
DISPLAY 0.617021 (-1990 4260);
PAINT ORANGE (-1990 4260);
FORCEPROP 2 LASTPIN (-2000 4200) $PN 106
J 0
(-1990 4210);
DISPLAY 0.617021 (-1990 4210);
PAINT ORANGE (-1990 4210);
FORCEPROP 2 LASTPIN (-2000 4150) $PN 260
J 0
(-1990 4160);
DISPLAY 0.617021 (-1990 4160);
PAINT ORANGE (-1990 4160);
FORCEPROP 2 LASTPIN (-2000 4100) $PN 115
J 0
(-1990 4110);
DISPLAY 0.617021 (-1990 4110);
PAINT ORANGE (-1990 4110);
FORCEPROP 2 LASTPIN (-2000 4050) $PN 253
J 0
(-1990 4060);
DISPLAY 0.617021 (-1990 4060);
PAINT ORANGE (-1990 4060);
FORCEPROP 2 LASTPIN (-2000 4000) $PN 108
J 0
(-1990 4010);
DISPLAY 0.617021 (-1990 4010);
PAINT ORANGE (-1990 4010);
FORCEPROP 2 LASTPIN (-2000 3950) $PN 247
J 0
(-1990 3960);
DISPLAY 0.617021 (-1990 3960);
PAINT ORANGE (-1990 3960);
FORCEPROP 2 LASTPIN (-2000 3900) $PN 102
J 0
(-1990 3910);
DISPLAY 0.617021 (-1990 3910);
PAINT ORANGE (-1990 3910);
FORCEPROP 2 LASTPIN (-2000 3850) $PN 240
J 0
(-1990 3860);
DISPLAY 0.617021 (-1990 3860);
PAINT ORANGE (-1990 3860);
FORCEPROP 2 LASTPIN (-2000 3800) $PN 95
J 0
(-1990 3810);
DISPLAY 0.617021 (-1990 3810);
PAINT ORANGE (-1990 3810);
FORCEPROP 2 LASTPIN (-2000 3750) $PN 249
J 0
(-1990 3760);
DISPLAY 0.617021 (-1990 3760);
PAINT ORANGE (-1990 3760);
FORCEPROP 2 LASTPIN (-2000 3700) $PN 104
J 0
(-1990 3710);
DISPLAY 0.617021 (-1990 3710);
PAINT ORANGE (-1990 3710);
FORCEPROP 2 LASTPIN (-2000 3650) $PN 242
J 0
(-1990 3660);
DISPLAY 0.617021 (-1990 3660);
PAINT ORANGE (-1990 3660);
FORCEPROP 2 LASTPIN (-2000 3600) $PN 97
J 0
(-1990 3610);
DISPLAY 0.617021 (-1990 3610);
PAINT ORANGE (-1990 3610);
FORCEPROP 2 LASTPIN (-2000 3550) $PN 188
J 0
(-1990 3560);
DISPLAY 0.617021 (-1990 3560);
PAINT ORANGE (-1990 3560);
FORCEPROP 2 LASTPIN (-2000 3500) $PN 43
J 0
(-1990 3510);
DISPLAY 0.617021 (-1990 3510);
PAINT ORANGE (-1990 3510);
FORCEPROP 2 LASTPIN (-2000 3450) $PN 181
J 0
(-1990 3460);
DISPLAY 0.617021 (-1990 3460);
PAINT ORANGE (-1990 3460);
FORCEPROP 2 LASTPIN (-2000 3400) $PN 36
J 0
(-1990 3410);
DISPLAY 0.617021 (-1990 3410);
PAINT ORANGE (-1990 3410);
FORCEPROP 2 LASTPIN (-2000 3350) $PN 190
J 0
(-1990 3360);
DISPLAY 0.617021 (-1990 3360);
PAINT ORANGE (-1990 3360);
FORCEPROP 2 LASTPIN (-2000 3300) $PN 45
J 0
(-1990 3310);
DISPLAY 0.617021 (-1990 3310);
PAINT ORANGE (-1990 3310);
FORCEPROP 2 LASTPIN (-2000 3250) $PN 183
J 0
(-1990 3260);
DISPLAY 0.617021 (-1990 3260);
PAINT ORANGE (-1990 3260);
FORCEPROP 2 LASTPIN (-2000 3200) $PN 38
J 0
(-1990 3210);
DISPLAY 0.617021 (-1990 3210);
PAINT ORANGE (-1990 3210);
FORCEPROP 2 LASTPIN (-2000 3150) $PN 177
J 0
(-1990 3160);
DISPLAY 0.617021 (-1990 3160);
PAINT ORANGE (-1990 3160);
FORCEPROP 2 LASTPIN (-2000 3100) $PN 32
J 0
(-1990 3110);
DISPLAY 0.617021 (-1990 3110);
PAINT ORANGE (-1990 3110);
FORCEPROP 2 LASTPIN (-2000 3050) $PN 170
J 0
(-1990 3060);
DISPLAY 0.617021 (-1990 3060);
PAINT ORANGE (-1990 3060);
FORCEPROP 2 LASTPIN (-2000 3000) $PN 25
J 0
(-1990 3010);
DISPLAY 0.617021 (-1990 3010);
PAINT ORANGE (-1990 3010);
FORCEPROP 2 LASTPIN (-2000 2950) $PN 179
J 0
(-1990 2960);
DISPLAY 0.617021 (-1990 2960);
PAINT ORANGE (-1990 2960);
FORCEPROP 2 LASTPIN (-2000 2900) $PN 34
J 0
(-1990 2910);
DISPLAY 0.617021 (-1990 2910);
PAINT ORANGE (-1990 2910);
FORCEPROP 2 LASTPIN (-2000 2850) $PN 172
J 0
(-1990 2860);
DISPLAY 0.617021 (-1990 2860);
PAINT ORANGE (-1990 2860);
FORCEPROP 2 LASTPIN (-2000 2800) $PN 27
J 0
(-1990 2810);
DISPLAY 0.617021 (-1990 2810);
PAINT ORANGE (-1990 2810);
FORCEPROP 2 LASTPIN (-2000 2750) $PN 166
J 0
(-1990 2760);
DISPLAY 0.617021 (-1990 2760);
PAINT ORANGE (-1990 2760);
FORCEPROP 2 LASTPIN (-2000 2700) $PN 21
J 0
(-1990 2710);
DISPLAY 0.617021 (-1990 2710);
PAINT ORANGE (-1990 2710);
FORCEPROP 2 LASTPIN (-2000 2650) $PN 159
J 0
(-1990 2660);
DISPLAY 0.617021 (-1990 2660);
PAINT ORANGE (-1990 2660);
FORCEPROP 2 LASTPIN (-2000 2600) $PN 14
J 0
(-1990 2610);
DISPLAY 0.617021 (-1990 2610);
PAINT ORANGE (-1990 2610);
FORCEPROP 2 LASTPIN (-2000 2550) $PN 168
J 0
(-1990 2560);
DISPLAY 0.617021 (-1990 2560);
PAINT ORANGE (-1990 2560);
FORCEPROP 2 LASTPIN (-2000 2500) $PN 23
J 0
(-1990 2510);
DISPLAY 0.617021 (-1990 2510);
PAINT ORANGE (-1990 2510);
FORCEPROP 2 LASTPIN (-2000 2450) $PN 161
J 0
(-1990 2460);
DISPLAY 0.617021 (-1990 2460);
PAINT ORANGE (-1990 2460);
FORCEPROP 2 LASTPIN (-2000 2400) $PN 16
J 0
(-1990 2410);
DISPLAY 0.617021 (-1990 2410);
PAINT ORANGE (-1990 2410);
FORCEPROP 2 LASTPIN (-2000 2350) $PN 155
J 0
(-1990 2360);
DISPLAY 0.617021 (-1990 2360);
PAINT ORANGE (-1990 2360);
FORCEPROP 2 LASTPIN (-2000 2300) $PN 10
J 0
(-1990 2310);
DISPLAY 0.617021 (-1990 2310);
PAINT ORANGE (-1990 2310);
FORCEPROP 2 LASTPIN (-2000 2250) $PN 148
J 0
(-1990 2260);
DISPLAY 0.617021 (-1990 2260);
PAINT ORANGE (-1990 2260);
FORCEPROP 2 LASTPIN (-2000 2200) $PN 3
J 0
(-1990 2210);
DISPLAY 0.617021 (-1990 2210);
PAINT ORANGE (-1990 2210);
FORCEPROP 2 LASTPIN (-2000 2150) $PN 157
J 0
(-1990 2160);
DISPLAY 0.617021 (-1990 2160);
PAINT ORANGE (-1990 2160);
FORCEPROP 2 LASTPIN (-2000 2100) $PN 12
J 0
(-1990 2110);
DISPLAY 0.617021 (-1990 2110);
PAINT ORANGE (-1990 2110);
FORCEPROP 2 LASTPIN (-2000 2050) $PN 150
J 0
(-1990 2060);
DISPLAY 0.617021 (-1990 2060);
PAINT ORANGE (-1990 2060);
FORCEPROP 2 LASTPIN (-2000 2000) $PN 5
J 0
(-1990 2010);
DISPLAY 0.617021 (-1990 2010);
PAINT ORANGE (-1990 2010);
FORCEPROP 2 LASTPIN (-3000 3400) $PN 203
J 2
(-3010 3410);
DISPLAY 0.617021 (-3010 3410);
PAINT ORANGE (-3010 3410);
FORCEPROP 2 LASTPIN (-3000 3350) $PN 60
J 2
(-3010 3360);
DISPLAY 0.617021 (-3010 3360);
PAINT ORANGE (-3010 3360);
FORCEPROP 2 LASTPIN (-3000 3950) $PN 218
J 2
(-3010 3960);
DISPLAY 0.617021 (-3010 3960);
PAINT ORANGE (-3010 3960);
FORCEPROP 2 LASTPIN (-3000 3900) $PN 219
J 2
(-3010 3910);
DISPLAY 0.617021 (-3010 3910);
PAINT ORANGE (-3010 3910);
FORCEPROP 2 LASTPIN (-3000 3850) $PN 74
J 2
(-3010 3860);
DISPLAY 0.617021 (-3010 3860);
PAINT ORANGE (-3010 3860);
FORCEPROP 2 LASTPIN (-3000 3800) $PN 75
J 2
(-3010 3810);
DISPLAY 0.617021 (-3010 3810);
PAINT ORANGE (-3010 3810);
FORCEPROP 2 LASTPIN (-3000 3100) $PN 199
J 2
(-3010 3110);
DISPLAY 0.617021 (-3010 3110);
PAINT ORANGE (-3010 3110);
FORCEPROP 2 LASTPIN (-3000 3050) $PN 54
J 2
(-3010 3060);
DISPLAY 0.617021 (-3010 3060);
PAINT ORANGE (-3010 3060);
FORCEPROP 2 LASTPIN (-3000 3000) $PN 192
J 2
(-3010 3010);
DISPLAY 0.617021 (-3010 3010);
PAINT ORANGE (-3010 3010);
FORCEPROP 2 LASTPIN (-3000 2950) $PN 47
J 2
(-3010 2960);
DISPLAY 0.617021 (-3010 2960);
PAINT ORANGE (-3010 2960);
FORCEPROP 2 LASTPIN (-3000 2900) $PN 201
J 2
(-3010 2910);
DISPLAY 0.617021 (-3010 2910);
PAINT ORANGE (-3010 2910);
FORCEPROP 2 LASTPIN (-3000 2850) $PN 56
J 2
(-3010 2860);
DISPLAY 0.617021 (-3010 2860);
PAINT ORANGE (-3010 2860);
FORCEPROP 2 LASTPIN (-3000 2800) $PN 194
J 2
(-3010 2810);
DISPLAY 0.617021 (-3010 2810);
PAINT ORANGE (-3010 2810);
FORCEPROP 2 LASTPIN (-3000 2750) $PN 49
J 2
(-3010 2760);
DISPLAY 0.617021 (-3010 2760);
PAINT ORANGE (-3010 2760);
FORCEPROP 2 LASTPIN (-3000 3700) $PN 235
J 2
(-3010 3710);
DISPLAY 0.617021 (-3010 3710);
PAINT ORANGE (-3010 3710);
FORCEPROP 2 LASTPIN (-3000 4100) $PN 207
J 2
(-3010 4110);
DISPLAY 0.617021 (-3010 4110);
PAINT ORANGE (-3010 4110);
FORCEPROP 2 LASTPIN (-3000 4050) $PN 63
J 2
(-3010 4060);
DISPLAY 0.617021 (-3010 4060);
PAINT ORANGE (-3010 4060);
FORCEPROP 2 LASTPIN (-3000 4200) $PN 224
J 2
(-3010 4210);
DISPLAY 0.617021 (-3010 4210);
PAINT ORANGE (-3010 4210);
FORCEPROP 2 LASTPIN (-3000 4150) $PN 81
J 2
(-3010 4160);
DISPLAY 0.617021 (-3010 4160);
PAINT ORANGE (-3010 4160);
FORCEPROP 2 LASTPIN (-3000 2500) $PN 208
J 2
(-3010 2510);
DISPLAY 0.617021 (-3010 2510);
PAINT ORANGE (-3010 2510);
FORCEPROP 2 LASTPIN (-3000 2450) $PN 62
J 2
(-3010 2460);
DISPLAY 0.617021 (-3010 2460);
PAINT ORANGE (-3010 2460);
FORCEPROP 2 LASTPIN (-3000 5150) $PN 234
J 2
(-3010 5160);
DISPLAY 0.617021 (-3010 5160);
PAINT ORANGE (-3010 5160);
FORCEPROP 2 LASTPIN (-3000 5100) $PN 82
J 2
(-3010 5110);
DISPLAY 0.617021 (-3010 5110);
PAINT ORANGE (-3010 5110);
FORCEPROP 2 LASTPIN (-3000 5050) $PN 86
J 2
(-3010 5060);
DISPLAY 0.617021 (-3010 5060);
PAINT ORANGE (-3010 5060);
FORCEPROP 2 LASTPIN (-3000 5000) $PN 228
J 2
(-3010 5010);
DISPLAY 0.617021 (-3010 5010);
PAINT ORANGE (-3010 5010);
FORCEPROP 2 LASTPIN (-3000 4950) $PN 232
J 2
(-3010 4960);
DISPLAY 0.617021 (-3010 4960);
PAINT ORANGE (-3010 4960);
FORCEPROP 2 LASTPIN (-3000 4900) $PN 65
J 2
(-3010 4910);
DISPLAY 0.617021 (-3010 4910);
PAINT ORANGE (-3010 4910);
FORCEPROP 2 LASTPIN (-3000 4850) $PN 210
J 2
(-3010 4860);
DISPLAY 0.617021 (-3010 4860);
PAINT ORANGE (-3010 4860);
FORCEPROP 2 LASTPIN (-3000 4800) $PN 225
J 2
(-3010 4810);
DISPLAY 0.617021 (-3010 4810);
PAINT ORANGE (-3010 4810);
FORCEPROP 2 LASTPIN (-3000 4750) $PN 66
J 2
(-3010 4760);
DISPLAY 0.617021 (-3010 4760);
PAINT ORANGE (-3010 4760);
FORCEPROP 2 LASTPIN (-3000 4700) $PN 68
J 2
(-3010 4710);
DISPLAY 0.617021 (-3010 4710);
PAINT ORANGE (-3010 4710);
FORCEPROP 2 LASTPIN (-3000 4650) $PN 211
J 2
(-3010 4660);
DISPLAY 0.617021 (-3010 4660);
PAINT ORANGE (-3010 4660);
FORCEPROP 2 LASTPIN (-3000 4600) $PN 69
J 2
(-3010 4610);
DISPLAY 0.617021 (-3010 4610);
PAINT ORANGE (-3010 4610);
FORCEPROP 2 LASTPIN (-3000 4550) $PN 213
J 2
(-3010 4560);
DISPLAY 0.617021 (-3010 4560);
PAINT ORANGE (-3010 4560);
FORCEPROP 2 LASTPIN (-3000 4500) $PN 214
J 2
(-3010 4510);
DISPLAY 0.617021 (-3010 4510);
PAINT ORANGE (-3010 4510);
FORCEPROP 2 LASTPIN (-3000 4450) $PN 71
J 2
(-3010 4460);
DISPLAY 0.617021 (-3010 4460);
PAINT ORANGE (-3010 4460);
FORCEPROP 2 LASTPIN (-3000 4400) $PN 216
J 2
(-3010 4410);
DISPLAY 0.617021 (-3010 4410);
PAINT ORANGE (-3010 4410);
FORCEPROP 2 LASTPIN (-3000 4350) $PN 72
J 2
(-3010 4360);
DISPLAY 0.617021 (-3010 4360);
PAINT ORANGE (-3010 4360);
FORCEPROP 2 LASTPIN (-3000 4300) $PN 79
J 2
(-3010 4310);
DISPLAY 0.617021 (-3010 4310);
PAINT ORANGE (-3010 4310);
FORCEPROP 1 LAST PACK_TYPE PIP
J 0
(-2950 5450);
PAINT SKYBLUE (-2950 5450);
DISPLAY INVISIBLE (-2950 5450);
FORCEPROP 2 LAST BOM_COST MEM
J 0
(-2450 2850);
PAINT ORANGE (-2450 2850);
DISPLAY INVISIBLE (-2450 2850);
FORCEPROP 2 LAST CDS_LIB mstr_sconn
J 0
(-2500 3500);
PAINT ORANGE (-2500 3500);
DISPLAY INVISIBLE (-2500 3500);
FORCEPROP 2 LAST SEC_TYPE PIP
J 0
(-2950 5450);
DISPLAY 1.021277 (-2950 5450);
PAINT ORANGE (-2950 5450);
DISPLAY INVISIBLE (-2950 5450);
FORCEPROP 2 LAST SEC 1
J 0
(-2950 5450);
DISPLAY 0.680851 (-2950 5450);
PAINT MONO (-2950 5450);
DISPLAY INVISIBLE (-2950 5450);
FORCEPROP 2 LAST CDS_LOCATION J4B1
J 0
(-2950 5400);
DISPLAY 0.617021 (-2950 5400);
PAINT AQUA (-2950 5400);
DISPLAY INVISIBLE (-2950 5400);
FORCEPROP 1 LAST PATH I111
J 0
(-2500 5350);
PAINT GREEN (-2500 5350);
DISPLAY INVISIBLE (-2500 5350);
FORCEPROP 2 LAST ROOM DDR4_CH_D
J 0
(-2450 2850);
PAINT ORANGE (-2450 2850);
DISPLAY INVISIBLE (-2450 2850);
FORCEADD TAP..6
(-3250 5150);
FORCEPROP 3 LASTPIN (-3200 5150) SIG_NAME M_D_MA<17>
J 0
(-3190 5160);
DISPLAY 0.659574 (-3190 5160);
PAINT MONO (-3190 5160);
DISPLAY INVISIBLE (-3190 5160);
FORCEPROP 1 LASTPIN (-3200 5150) BN 17
J 0
(-3250 5160);
DISPLAY 0.617021 (-3250 5160);
PAINT PINK (-3250 5160);
FORCEPROP 2 LAST CDS_LIB mstr_standard
J 0
(-3250 5150);
DISPLAY 0.787234 (-3250 5150);
PAINT MONO (-3250 5150);
DISPLAY INVISIBLE (-3250 5150);
FORCEPROP 1 LAST BODY_TYPE PLUMBING
J 0
(-3250 5100);
DISPLAY 1.234043 (-3250 5100);
PAINT GREEN (-3250 5100);
DISPLAY INVISIBLE (-3250 5100);
FORCEPROP 1 LAST HDL_TAP TRUE
J 0
(-2925 5025);
DISPLAY 1.234043 (-2925 5025);
PAINT GREEN (-2925 5025);
DISPLAY INVISIBLE (-2925 5025);
FORCEPROP 1 LAST PATH I112
J 0
(-3250 5150);
DISPLAY 0.936170 (-3250 5150);
PAINT GREEN (-3250 5150);
DISPLAY INVISIBLE (-3250 5150);
FORCEADD TAP..6
(-3250 5100);
FORCEPROP 3 LASTPIN (-3200 5100) SIG_NAME M_D_MA<16>
J 0
(-3190 5110);
DISPLAY 0.659574 (-3190 5110);
PAINT MONO (-3190 5110);
DISPLAY INVISIBLE (-3190 5110);
FORCEPROP 1 LASTPIN (-3200 5100) BN 16
J 0
(-3250 5110);
DISPLAY 0.617021 (-3250 5110);
PAINT PINK (-3250 5110);
FORCEPROP 2 LAST CDS_LIB mstr_standard
J 2
(-3250 5100);
DISPLAY 0.787234 (-3250 5100);
PAINT MONO (-3250 5100);
DISPLAY INVISIBLE (-3250 5100);
FORCEPROP 1 LAST BODY_TYPE PLUMBING
J 0
(-3250 5050);
DISPLAY 1.234043 (-3250 5050);
PAINT GREEN (-3250 5050);
DISPLAY INVISIBLE (-3250 5050);
FORCEPROP 1 LAST HDL_TAP TRUE
J 0
(-2925 4975);
DISPLAY 1.234043 (-2925 4975);
PAINT GREEN (-2925 4975);
DISPLAY INVISIBLE (-2925 4975);
FORCEPROP 1 LAST PATH I113
J 0
(-3250 5100);
DISPLAY 0.936170 (-3250 5100);
PAINT GREEN (-3250 5100);
DISPLAY INVISIBLE (-3250 5100);
FORCEADD TAP..6
(-3250 5050);
FORCEPROP 3 LASTPIN (-3200 5050) SIG_NAME M_D_MA<15>
J 0
(-3190 5060);
DISPLAY 0.659574 (-3190 5060);
PAINT MONO (-3190 5060);
DISPLAY INVISIBLE (-3190 5060);
FORCEPROP 1 LASTPIN (-3200 5050) BN 15
J 0
(-3250 5060);
DISPLAY 0.617021 (-3250 5060);
PAINT PINK (-3250 5060);
FORCEPROP 2 LAST CDS_LIB mstr_standard
J 2
(-3250 5050);
DISPLAY 0.787234 (-3250 5050);
PAINT MONO (-3250 5050);
DISPLAY INVISIBLE (-3250 5050);
FORCEPROP 1 LAST BODY_TYPE PLUMBING
J 0
(-3250 5000);
DISPLAY 1.234043 (-3250 5000);
PAINT GREEN (-3250 5000);
DISPLAY INVISIBLE (-3250 5000);
FORCEPROP 1 LAST HDL_TAP TRUE
J 0
(-2925 4925);
DISPLAY 1.234043 (-2925 4925);
PAINT GREEN (-2925 4925);
DISPLAY INVISIBLE (-2925 4925);
FORCEPROP 1 LAST PATH I114
J 0
(-3250 5050);
DISPLAY 0.936170 (-3250 5050);
PAINT GREEN (-3250 5050);
DISPLAY INVISIBLE (-3250 5050);
FORCEADD TAP..6
(-3250 5000);
FORCEPROP 3 LASTPIN (-3200 5000) SIG_NAME M_D_MA<14>
J 0
(-3190 5010);
DISPLAY 0.659574 (-3190 5010);
PAINT MONO (-3190 5010);
DISPLAY INVISIBLE (-3190 5010);
FORCEPROP 1 LASTPIN (-3200 5000) BN 14
J 0
(-3250 5010);
DISPLAY 0.617021 (-3250 5010);
PAINT PINK (-3250 5010);
FORCEPROP 2 LAST CDS_LIB mstr_standard
J 2
(-3250 5000);
DISPLAY 0.787234 (-3250 5000);
PAINT MONO (-3250 5000);
DISPLAY INVISIBLE (-3250 5000);
FORCEPROP 1 LAST BODY_TYPE PLUMBING
J 0
(-3250 4950);
DISPLAY 1.234043 (-3250 4950);
PAINT GREEN (-3250 4950);
DISPLAY INVISIBLE (-3250 4950);
FORCEPROP 1 LAST HDL_TAP TRUE
J 0
(-2925 4875);
DISPLAY 1.234043 (-2925 4875);
PAINT GREEN (-2925 4875);
DISPLAY INVISIBLE (-2925 4875);
FORCEPROP 1 LAST PATH I115
J 0
(-3250 5000);
DISPLAY 0.936170 (-3250 5000);
PAINT GREEN (-3250 5000);
DISPLAY INVISIBLE (-3250 5000);
FORCEADD TAP..6
(-3250 4950);
FORCEPROP 3 LASTPIN (-3200 4950) SIG_NAME M_D_MA<13>
J 0
(-3190 4960);
DISPLAY 0.659574 (-3190 4960);
PAINT MONO (-3190 4960);
DISPLAY INVISIBLE (-3190 4960);
FORCEPROP 1 LASTPIN (-3200 4950) BN 13
J 0
(-3250 4960);
DISPLAY 0.617021 (-3250 4960);
PAINT PINK (-3250 4960);
FORCEPROP 2 LAST CDS_LIB mstr_standard
J 2
(-3250 4950);
DISPLAY 0.787234 (-3250 4950);
PAINT MONO (-3250 4950);
DISPLAY INVISIBLE (-3250 4950);
FORCEPROP 1 LAST BODY_TYPE PLUMBING
J 0
(-3250 4900);
DISPLAY 1.234043 (-3250 4900);
PAINT GREEN (-3250 4900);
DISPLAY INVISIBLE (-3250 4900);
FORCEPROP 1 LAST HDL_TAP TRUE
J 0
(-2925 4825);
DISPLAY 1.234043 (-2925 4825);
PAINT GREEN (-2925 4825);
DISPLAY INVISIBLE (-2925 4825);
FORCEPROP 1 LAST PATH I116
J 0
(-3250 4950);
DISPLAY 0.936170 (-3250 4950);
PAINT GREEN (-3250 4950);
DISPLAY INVISIBLE (-3250 4950);
FORCEADD TAP..6
(-3250 4900);
FORCEPROP 3 LASTPIN (-3200 4900) SIG_NAME M_D_MA<12>
J 0
(-3190 4910);
DISPLAY 0.659574 (-3190 4910);
PAINT MONO (-3190 4910);
DISPLAY INVISIBLE (-3190 4910);
FORCEPROP 1 LASTPIN (-3200 4900) BN 12
J 0
(-3250 4910);
DISPLAY 0.617021 (-3250 4910);
PAINT PINK (-3250 4910);
FORCEPROP 2 LAST CDS_LIB mstr_standard
J 2
(-3250 4900);
DISPLAY 0.787234 (-3250 4900);
PAINT MONO (-3250 4900);
DISPLAY INVISIBLE (-3250 4900);
FORCEPROP 1 LAST BODY_TYPE PLUMBING
J 0
(-3250 4850);
DISPLAY 1.234043 (-3250 4850);
PAINT GREEN (-3250 4850);
DISPLAY INVISIBLE (-3250 4850);
FORCEPROP 1 LAST HDL_TAP TRUE
J 0
(-2925 4775);
DISPLAY 1.234043 (-2925 4775);
PAINT GREEN (-2925 4775);
DISPLAY INVISIBLE (-2925 4775);
FORCEPROP 1 LAST PATH I117
J 0
(-3250 4900);
DISPLAY 0.936170 (-3250 4900);
PAINT GREEN (-3250 4900);
DISPLAY INVISIBLE (-3250 4900);
FORCEADD TAP..6
(-3250 4850);
FORCEPROP 3 LASTPIN (-3200 4850) SIG_NAME M_D_MA<11>
J 0
(-3190 4860);
DISPLAY 0.659574 (-3190 4860);
PAINT MONO (-3190 4860);
DISPLAY INVISIBLE (-3190 4860);
FORCEPROP 1 LASTPIN (-3200 4850) BN 11
J 0
(-3250 4860);
DISPLAY 0.617021 (-3250 4860);
PAINT PINK (-3250 4860);
FORCEPROP 2 LAST CDS_LIB mstr_standard
J 2
(-3250 4850);
DISPLAY 0.787234 (-3250 4850);
PAINT MONO (-3250 4850);
DISPLAY INVISIBLE (-3250 4850);
FORCEPROP 1 LAST BODY_TYPE PLUMBING
J 0
(-3250 4800);
DISPLAY 1.234043 (-3250 4800);
PAINT GREEN (-3250 4800);
DISPLAY INVISIBLE (-3250 4800);
FORCEPROP 1 LAST HDL_TAP TRUE
J 0
(-2925 4725);
DISPLAY 1.234043 (-2925 4725);
PAINT GREEN (-2925 4725);
DISPLAY INVISIBLE (-2925 4725);
FORCEPROP 1 LAST PATH I118
J 0
(-3250 4850);
DISPLAY 0.936170 (-3250 4850);
PAINT GREEN (-3250 4850);
DISPLAY INVISIBLE (-3250 4850);
FORCEADD TAP..6
(-3250 4800);
FORCEPROP 3 LASTPIN (-3200 4800) SIG_NAME M_D_MA<10>
J 0
(-3190 4810);
DISPLAY 0.659574 (-3190 4810);
PAINT MONO (-3190 4810);
DISPLAY INVISIBLE (-3190 4810);
FORCEPROP 1 LASTPIN (-3200 4800) BN 10
J 0
(-3250 4810);
DISPLAY 0.617021 (-3250 4810);
PAINT PINK (-3250 4810);
FORCEPROP 2 LAST CDS_LIB mstr_standard
J 2
(-3250 4800);
DISPLAY 0.787234 (-3250 4800);
PAINT MONO (-3250 4800);
DISPLAY INVISIBLE (-3250 4800);
FORCEPROP 1 LAST BODY_TYPE PLUMBING
J 0
(-3250 4750);
DISPLAY 1.234043 (-3250 4750);
PAINT GREEN (-3250 4750);
DISPLAY INVISIBLE (-3250 4750);
FORCEPROP 1 LAST HDL_TAP TRUE
J 0
(-2925 4675);
DISPLAY 1.234043 (-2925 4675);
PAINT GREEN (-2925 4675);
DISPLAY INVISIBLE (-2925 4675);
FORCEPROP 1 LAST PATH I119
J 0
(-3250 4800);
DISPLAY 0.936170 (-3250 4800);
PAINT GREEN (-3250 4800);
DISPLAY INVISIBLE (-3250 4800);
FORCEADD TAP..6
R 2
(650 4900);
FORCEPROP 3 LASTPIN (600 4900) SIG_NAME M_D_DQS_DP<14>
J 0
(610 4910);
DISPLAY 0.659574 (610 4910);
PAINT MONO (610 4910);
DISPLAY INVISIBLE (610 4910);
FORCEPROP 1 LASTPIN (600 4900) BN 14
J 2
(650 4910);
DISPLAY 0.617021 (650 4910);
PAINT PINK (650 4910);
FORCEPROP 2 LAST CDS_LIB mstr_standard
J 0
(650 4900);
DISPLAY 0.787234 (650 4900);
PAINT MONO (650 4900);
DISPLAY INVISIBLE (650 4900);
FORCEPROP 1 LAST BODY_TYPE PLUMBING
J 2
(650 4850);
DISPLAY 1.234043 (650 4850);
PAINT GREEN (650 4850);
DISPLAY INVISIBLE (650 4850);
FORCEPROP 1 LAST HDL_TAP TRUE
J 2
(325 4775);
DISPLAY 1.234043 (325 4775);
PAINT GREEN (325 4775);
DISPLAY INVISIBLE (325 4775);
FORCEPROP 1 LAST PATH I12
J 2
(650 4900);
DISPLAY 0.936170 (650 4900);
PAINT GREEN (650 4900);
DISPLAY INVISIBLE (650 4900);
FORCEADD TAP..6
(-3250 4750);
FORCEPROP 3 LASTPIN (-3200 4750) SIG_NAME M_D_MA<9>
J 0
(-3190 4760);
DISPLAY 0.659574 (-3190 4760);
PAINT MONO (-3190 4760);
DISPLAY INVISIBLE (-3190 4760);
FORCEPROP 1 LASTPIN (-3200 4750) BN 9
J 0
(-3250 4760);
DISPLAY 0.617021 (-3250 4760);
PAINT PINK (-3250 4760);
FORCEPROP 2 LAST CDS_LIB mstr_standard
J 2
(-3250 4750);
DISPLAY 0.787234 (-3250 4750);
PAINT MONO (-3250 4750);
DISPLAY INVISIBLE (-3250 4750);
FORCEPROP 1 LAST BODY_TYPE PLUMBING
J 0
(-3250 4700);
DISPLAY 1.234043 (-3250 4700);
PAINT GREEN (-3250 4700);
DISPLAY INVISIBLE (-3250 4700);
FORCEPROP 1 LAST HDL_TAP TRUE
J 0
(-2925 4625);
DISPLAY 1.234043 (-2925 4625);
PAINT GREEN (-2925 4625);
DISPLAY INVISIBLE (-2925 4625);
FORCEPROP 1 LAST PATH I120
J 0
(-3250 4750);
DISPLAY 0.936170 (-3250 4750);
PAINT GREEN (-3250 4750);
DISPLAY INVISIBLE (-3250 4750);
FORCEADD TAP..6
(-3250 4700);
FORCEPROP 3 LASTPIN (-3200 4700) SIG_NAME M_D_MA<8>
J 0
(-3190 4710);
DISPLAY 0.659574 (-3190 4710);
PAINT MONO (-3190 4710);
DISPLAY INVISIBLE (-3190 4710);
FORCEPROP 1 LASTPIN (-3200 4700) BN 8
J 0
(-3250 4710);
DISPLAY 0.617021 (-3250 4710);
PAINT PINK (-3250 4710);
FORCEPROP 2 LAST CDS_LIB mstr_standard
J 2
(-3250 4700);
DISPLAY 0.787234 (-3250 4700);
PAINT MONO (-3250 4700);
DISPLAY INVISIBLE (-3250 4700);
FORCEPROP 1 LAST BODY_TYPE PLUMBING
J 0
(-3250 4650);
DISPLAY 1.234043 (-3250 4650);
PAINT GREEN (-3250 4650);
DISPLAY INVISIBLE (-3250 4650);
FORCEPROP 1 LAST HDL_TAP TRUE
J 0
(-2925 4575);
DISPLAY 1.234043 (-2925 4575);
PAINT GREEN (-2925 4575);
DISPLAY INVISIBLE (-2925 4575);
FORCEPROP 1 LAST PATH I121
J 0
(-3250 4700);
DISPLAY 0.936170 (-3250 4700);
PAINT GREEN (-3250 4700);
DISPLAY INVISIBLE (-3250 4700);
FORCEADD TAP..6
(-3250 4650);
FORCEPROP 3 LASTPIN (-3200 4650) SIG_NAME M_D_MA<7>
J 0
(-3190 4660);
DISPLAY 0.659574 (-3190 4660);
PAINT MONO (-3190 4660);
DISPLAY INVISIBLE (-3190 4660);
FORCEPROP 1 LASTPIN (-3200 4650) BN 7
J 0
(-3250 4660);
DISPLAY 0.617021 (-3250 4660);
PAINT PINK (-3250 4660);
FORCEPROP 2 LAST CDS_LIB mstr_standard
J 2
(-3250 4650);
DISPLAY 0.787234 (-3250 4650);
PAINT MONO (-3250 4650);
DISPLAY INVISIBLE (-3250 4650);
FORCEPROP 1 LAST BODY_TYPE PLUMBING
J 0
(-3250 4600);
DISPLAY 1.234043 (-3250 4600);
PAINT GREEN (-3250 4600);
DISPLAY INVISIBLE (-3250 4600);
FORCEPROP 1 LAST HDL_TAP TRUE
J 0
(-2925 4525);
DISPLAY 1.234043 (-2925 4525);
PAINT GREEN (-2925 4525);
DISPLAY INVISIBLE (-2925 4525);
FORCEPROP 1 LAST PATH I122
J 0
(-3250 4650);
DISPLAY 0.936170 (-3250 4650);
PAINT GREEN (-3250 4650);
DISPLAY INVISIBLE (-3250 4650);
FORCEADD TAP..6
(-3250 4600);
FORCEPROP 3 LASTPIN (-3200 4600) SIG_NAME M_D_MA<6>
J 0
(-3190 4610);
DISPLAY 0.659574 (-3190 4610);
PAINT MONO (-3190 4610);
DISPLAY INVISIBLE (-3190 4610);
FORCEPROP 1 LASTPIN (-3200 4600) BN 6
J 0
(-3250 4610);
DISPLAY 0.617021 (-3250 4610);
PAINT PINK (-3250 4610);
FORCEPROP 2 LAST CDS_LIB mstr_standard
J 2
(-3250 4600);
DISPLAY 0.787234 (-3250 4600);
PAINT MONO (-3250 4600);
DISPLAY INVISIBLE (-3250 4600);
FORCEPROP 1 LAST BODY_TYPE PLUMBING
J 0
(-3250 4550);
DISPLAY 1.234043 (-3250 4550);
PAINT GREEN (-3250 4550);
DISPLAY INVISIBLE (-3250 4550);
FORCEPROP 1 LAST HDL_TAP TRUE
J 0
(-2925 4475);
DISPLAY 1.234043 (-2925 4475);
PAINT GREEN (-2925 4475);
DISPLAY INVISIBLE (-2925 4475);
FORCEPROP 1 LAST PATH I123
J 0
(-3250 4600);
DISPLAY 0.936170 (-3250 4600);
PAINT GREEN (-3250 4600);
DISPLAY INVISIBLE (-3250 4600);
FORCEADD TAP..6
(-3250 4550);
FORCEPROP 3 LASTPIN (-3200 4550) SIG_NAME M_D_MA<5>
J 0
(-3190 4560);
DISPLAY 0.659574 (-3190 4560);
PAINT MONO (-3190 4560);
DISPLAY INVISIBLE (-3190 4560);
FORCEPROP 1 LASTPIN (-3200 4550) BN 5
J 0
(-3250 4560);
DISPLAY 0.617021 (-3250 4560);
PAINT PINK (-3250 4560);
FORCEPROP 2 LAST CDS_LIB mstr_standard
J 2
(-3250 4550);
DISPLAY 0.787234 (-3250 4550);
PAINT MONO (-3250 4550);
DISPLAY INVISIBLE (-3250 4550);
FORCEPROP 1 LAST BODY_TYPE PLUMBING
J 0
(-3250 4500);
DISPLAY 1.234043 (-3250 4500);
PAINT GREEN (-3250 4500);
DISPLAY INVISIBLE (-3250 4500);
FORCEPROP 1 LAST HDL_TAP TRUE
J 0
(-2925 4425);
DISPLAY 1.234043 (-2925 4425);
PAINT GREEN (-2925 4425);
DISPLAY INVISIBLE (-2925 4425);
FORCEPROP 1 LAST PATH I124
J 0
(-3250 4550);
DISPLAY 0.936170 (-3250 4550);
PAINT GREEN (-3250 4550);
DISPLAY INVISIBLE (-3250 4550);
FORCEADD TAP..6
(-3250 4500);
FORCEPROP 3 LASTPIN (-3200 4500) SIG_NAME M_D_MA<4>
J 0
(-3190 4510);
DISPLAY 0.659574 (-3190 4510);
PAINT MONO (-3190 4510);
DISPLAY INVISIBLE (-3190 4510);
FORCEPROP 1 LASTPIN (-3200 4500) BN 4
J 0
(-3250 4510);
DISPLAY 0.617021 (-3250 4510);
PAINT PINK (-3250 4510);
FORCEPROP 2 LAST CDS_LIB mstr_standard
J 2
(-3250 4500);
DISPLAY 0.787234 (-3250 4500);
PAINT MONO (-3250 4500);
DISPLAY INVISIBLE (-3250 4500);
FORCEPROP 1 LAST BODY_TYPE PLUMBING
J 0
(-3250 4450);
DISPLAY 1.234043 (-3250 4450);
PAINT GREEN (-3250 4450);
DISPLAY INVISIBLE (-3250 4450);
FORCEPROP 1 LAST HDL_TAP TRUE
J 0
(-2925 4375);
DISPLAY 1.234043 (-2925 4375);
PAINT GREEN (-2925 4375);
DISPLAY INVISIBLE (-2925 4375);
FORCEPROP 1 LAST PATH I125
J 0
(-3250 4500);
DISPLAY 0.936170 (-3250 4500);
PAINT GREEN (-3250 4500);
DISPLAY INVISIBLE (-3250 4500);
FORCEADD TAP..6
(-3250 4450);
FORCEPROP 3 LASTPIN (-3200 4450) SIG_NAME M_D_MA<3>
J 0
(-3190 4460);
DISPLAY 0.659574 (-3190 4460);
PAINT MONO (-3190 4460);
DISPLAY INVISIBLE (-3190 4460);
FORCEPROP 1 LASTPIN (-3200 4450) BN 3
J 0
(-3250 4460);
DISPLAY 0.617021 (-3250 4460);
PAINT PINK (-3250 4460);
FORCEPROP 2 LAST CDS_LIB mstr_standard
J 2
(-3250 4450);
DISPLAY 0.787234 (-3250 4450);
PAINT MONO (-3250 4450);
DISPLAY INVISIBLE (-3250 4450);
FORCEPROP 1 LAST BODY_TYPE PLUMBING
J 0
(-3250 4400);
DISPLAY 1.234043 (-3250 4400);
PAINT GREEN (-3250 4400);
DISPLAY INVISIBLE (-3250 4400);
FORCEPROP 1 LAST HDL_TAP TRUE
J 0
(-2925 4325);
DISPLAY 1.234043 (-2925 4325);
PAINT GREEN (-2925 4325);
DISPLAY INVISIBLE (-2925 4325);
FORCEPROP 1 LAST PATH I126
J 0
(-3250 4450);
DISPLAY 0.936170 (-3250 4450);
PAINT GREEN (-3250 4450);
DISPLAY INVISIBLE (-3250 4450);
FORCEADD TAP..6
(-3250 4400);
FORCEPROP 3 LASTPIN (-3200 4400) SIG_NAME M_D_MA<2>
J 0
(-3190 4410);
DISPLAY 0.659574 (-3190 4410);
PAINT MONO (-3190 4410);
DISPLAY INVISIBLE (-3190 4410);
FORCEPROP 1 LASTPIN (-3200 4400) BN 2
J 0
(-3250 4410);
DISPLAY 0.617021 (-3250 4410);
PAINT PINK (-3250 4410);
FORCEPROP 2 LAST CDS_LIB mstr_standard
J 2
(-3250 4400);
DISPLAY 0.787234 (-3250 4400);
PAINT MONO (-3250 4400);
DISPLAY INVISIBLE (-3250 4400);
FORCEPROP 1 LAST BODY_TYPE PLUMBING
J 0
(-3250 4350);
DISPLAY 1.234043 (-3250 4350);
PAINT GREEN (-3250 4350);
DISPLAY INVISIBLE (-3250 4350);
FORCEPROP 1 LAST HDL_TAP TRUE
J 0
(-2925 4275);
DISPLAY 1.234043 (-2925 4275);
PAINT GREEN (-2925 4275);
DISPLAY INVISIBLE (-2925 4275);
FORCEPROP 1 LAST PATH I127
J 0
(-3250 4400);
DISPLAY 0.936170 (-3250 4400);
PAINT GREEN (-3250 4400);
DISPLAY INVISIBLE (-3250 4400);
FORCEADD TAP..6
(-3250 4350);
FORCEPROP 3 LASTPIN (-3200 4350) SIG_NAME M_D_MA<1>
J 0
(-3190 4360);
DISPLAY 0.659574 (-3190 4360);
PAINT MONO (-3190 4360);
DISPLAY INVISIBLE (-3190 4360);
FORCEPROP 1 LASTPIN (-3200 4350) BN 1
J 0
(-3250 4360);
DISPLAY 0.617021 (-3250 4360);
PAINT PINK (-3250 4360);
FORCEPROP 2 LAST CDS_LIB mstr_standard
J 2
(-3250 4350);
DISPLAY 0.787234 (-3250 4350);
PAINT MONO (-3250 4350);
DISPLAY INVISIBLE (-3250 4350);
FORCEPROP 1 LAST BODY_TYPE PLUMBING
J 0
(-3250 4300);
DISPLAY 1.234043 (-3250 4300);
PAINT GREEN (-3250 4300);
DISPLAY INVISIBLE (-3250 4300);
FORCEPROP 1 LAST HDL_TAP TRUE
J 0
(-2925 4225);
DISPLAY 1.234043 (-2925 4225);
PAINT GREEN (-2925 4225);
DISPLAY INVISIBLE (-2925 4225);
FORCEPROP 1 LAST PATH I128
J 0
(-3250 4350);
DISPLAY 0.936170 (-3250 4350);
PAINT GREEN (-3250 4350);
DISPLAY INVISIBLE (-3250 4350);
FORCEADD TAP..6
(-3250 4300);
FORCEPROP 3 LASTPIN (-3200 4300) SIG_NAME M_D_MA<0>
J 0
(-3190 4310);
DISPLAY 0.659574 (-3190 4310);
PAINT MONO (-3190 4310);
DISPLAY INVISIBLE (-3190 4310);
FORCEPROP 1 LASTPIN (-3200 4300) BN 0
J 0
(-3250 4310);
DISPLAY 0.617021 (-3250 4310);
PAINT PINK (-3250 4310);
FORCEPROP 2 LAST CDS_LIB mstr_standard
J 2
(-3250 4300);
DISPLAY 0.787234 (-3250 4300);
PAINT MONO (-3250 4300);
DISPLAY INVISIBLE (-3250 4300);
FORCEPROP 1 LAST BODY_TYPE PLUMBING
J 0
(-3250 4250);
DISPLAY 1.234043 (-3250 4250);
PAINT GREEN (-3250 4250);
DISPLAY INVISIBLE (-3250 4250);
FORCEPROP 1 LAST HDL_TAP TRUE
J 0
(-2925 4175);
DISPLAY 1.234043 (-2925 4175);
PAINT GREEN (-2925 4175);
DISPLAY INVISIBLE (-2925 4175);
FORCEPROP 1 LAST PATH I129
J 0
(-3250 4300);
DISPLAY 0.936170 (-3250 4300);
PAINT GREEN (-3250 4300);
DISPLAY INVISIBLE (-3250 4300);
FORCEADD TAP..6
R 2
(650 4800);
FORCEPROP 3 LASTPIN (600 4800) SIG_NAME M_D_DQS_DP<13>
J 0
(610 4810);
DISPLAY 0.659574 (610 4810);
PAINT MONO (610 4810);
DISPLAY INVISIBLE (610 4810);
FORCEPROP 1 LASTPIN (600 4800) BN 13
J 2
(650 4810);
DISPLAY 0.617021 (650 4810);
PAINT PINK (650 4810);
FORCEPROP 2 LAST CDS_LIB mstr_standard
J 0
(650 4800);
DISPLAY 0.787234 (650 4800);
PAINT MONO (650 4800);
DISPLAY INVISIBLE (650 4800);
FORCEPROP 1 LAST BODY_TYPE PLUMBING
J 2
(650 4750);
DISPLAY 1.234043 (650 4750);
PAINT GREEN (650 4750);
DISPLAY INVISIBLE (650 4750);
FORCEPROP 1 LAST HDL_TAP TRUE
J 2
(325 4675);
DISPLAY 1.234043 (325 4675);
PAINT GREEN (325 4675);
DISPLAY INVISIBLE (325 4675);
FORCEPROP 1 LAST PATH I13
J 2
(650 4800);
DISPLAY 0.936170 (650 4800);
PAINT GREEN (650 4800);
DISPLAY INVISIBLE (650 4800);
FORCEADD TAP..6
(-3250 4200);
FORCEPROP 3 LASTPIN (-3200 4200) SIG_NAME M_D_BA<1>
J 0
(-3190 4210);
DISPLAY 0.659574 (-3190 4210);
PAINT MONO (-3190 4210);
DISPLAY INVISIBLE (-3190 4210);
FORCEPROP 1 LASTPIN (-3200 4200) BN 1
J 0
(-3250 4210);
DISPLAY 0.617021 (-3250 4210);
PAINT PINK (-3250 4210);
FORCEPROP 2 LAST CDS_LIB mstr_standard
J 0
(-3250 4200);
DISPLAY 0.787234 (-3250 4200);
PAINT MONO (-3250 4200);
DISPLAY INVISIBLE (-3250 4200);
FORCEPROP 1 LAST BODY_TYPE PLUMBING
J 0
(-3250 4150);
DISPLAY 1.234043 (-3250 4150);
PAINT GREEN (-3250 4150);
DISPLAY INVISIBLE (-3250 4150);
FORCEPROP 1 LAST HDL_TAP TRUE
J 0
(-2925 4075);
DISPLAY 1.234043 (-2925 4075);
PAINT GREEN (-2925 4075);
DISPLAY INVISIBLE (-2925 4075);
FORCEPROP 1 LAST PATH I130
J 0
(-3250 4200);
DISPLAY 0.936170 (-3250 4200);
PAINT GREEN (-3250 4200);
DISPLAY INVISIBLE (-3250 4200);
FORCEADD OFFPAGE..1
(-4000 5200);
FORCEPROP 2 LAST $XR1 50 
J 0
(-4251 5164);
DISPLAY 0.638298 (-4251 5164);
PAINT MONO (-4251 5164);
FORCEPROP 2 LAST $XR0 26 
J 0
(-4251 5200);
DISPLAY 0.638298 (-4251 5200);
PAINT MONO (-4251 5200);
FORCEPROP 2 LAST CDS_LIB mstr_standard
J 0
(-4000 5200);
DISPLAY 0.787234 (-4000 5200);
PAINT MONO (-4000 5200);
DISPLAY INVISIBLE (-4000 5200);
FORCEPROP 1 LAST OFFPAGE TRUE
J 0
(-3675 5075);
DISPLAY 0.936170 (-3675 5075);
PAINT GREEN (-3675 5075);
DISPLAY INVISIBLE (-3675 5075);
FORCEPROP 1 LAST COMMENT_BODY TRUE
J 0
(-3875 5100);
DISPLAY 0.936170 (-3875 5100);
PAINT GREEN (-3875 5100);
DISPLAY INVISIBLE (-3875 5100);
FORCEPROP 2 LAST PATH I131
J 0
(-3950 5275);
DISPLAY 0.787234 (-3950 5275);
PAINT MONO (-3950 5275);
DISPLAY INVISIBLE (-3950 5275);
FORCEADD OFFPAGE..1
(-4000 4250);
FORCEPROP 2 LAST $XR0 26 
J 0
(-4251 4250);
DISPLAY 0.638298 (-4251 4250);
PAINT MONO (-4251 4250);
FORCEPROP 2 LAST $XR1 50 
J 0
(-4341 4250);
DISPLAY 0.638298 (-4341 4250);
PAINT MONO (-4341 4250);
FORCEPROP 2 LAST CDS_LIB mstr_standard
J 0
(-4000 4250);
DISPLAY 0.787234 (-4000 4250);
PAINT MONO (-4000 4250);
DISPLAY INVISIBLE (-4000 4250);
FORCEPROP 1 LAST OFFPAGE TRUE
J 0
(-3675 4125);
DISPLAY 0.936170 (-3675 4125);
PAINT GREEN (-3675 4125);
DISPLAY INVISIBLE (-3675 4125);
FORCEPROP 1 LAST COMMENT_BODY TRUE
J 0
(-3875 4150);
DISPLAY 0.936170 (-3875 4150);
PAINT GREEN (-3875 4150);
DISPLAY INVISIBLE (-3875 4150);
FORCEPROP 2 LAST PATH I132
J 0
(-3950 4325);
DISPLAY 0.787234 (-3950 4325);
PAINT MONO (-3950 4325);
DISPLAY INVISIBLE (-3950 4325);
FORCEADD TAP..6
(-3250 4150);
FORCEPROP 3 LASTPIN (-3200 4150) SIG_NAME M_D_BA<0>
J 0
(-3190 4160);
DISPLAY 0.659574 (-3190 4160);
PAINT MONO (-3190 4160);
DISPLAY INVISIBLE (-3190 4160);
FORCEPROP 1 LASTPIN (-3200 4150) BN 0
J 0
(-3250 4160);
DISPLAY 0.617021 (-3250 4160);
PAINT PINK (-3250 4160);
FORCEPROP 2 LAST CDS_LIB mstr_standard
J 0
(-3250 4150);
DISPLAY 0.787234 (-3250 4150);
PAINT MONO (-3250 4150);
DISPLAY INVISIBLE (-3250 4150);
FORCEPROP 1 LAST BODY_TYPE PLUMBING
J 0
(-3250 4100);
DISPLAY 1.234043 (-3250 4100);
PAINT GREEN (-3250 4100);
DISPLAY INVISIBLE (-3250 4100);
FORCEPROP 1 LAST HDL_TAP TRUE
J 0
(-2925 4025);
DISPLAY 1.234043 (-2925 4025);
PAINT GREEN (-2925 4025);
DISPLAY INVISIBLE (-2925 4025);
FORCEPROP 1 LAST PATH I133
J 0
(-3250 4150);
DISPLAY 0.936170 (-3250 4150);
PAINT GREEN (-3250 4150);
DISPLAY INVISIBLE (-3250 4150);
FORCEADD TAP..6
(-3250 4100);
FORCEPROP 3 LASTPIN (-3200 4100) SIG_NAME M_D_BG<1>
J 0
(-3190 4110);
DISPLAY 0.659574 (-3190 4110);
PAINT MONO (-3190 4110);
DISPLAY INVISIBLE (-3190 4110);
FORCEPROP 1 LASTPIN (-3200 4100) BN 1
J 0
(-3250 4110);
DISPLAY 0.617021 (-3250 4110);
PAINT PINK (-3250 4110);
FORCEPROP 2 LAST CDS_LIB mstr_standard
J 0
(-3250 4100);
DISPLAY 0.787234 (-3250 4100);
PAINT MONO (-3250 4100);
DISPLAY INVISIBLE (-3250 4100);
FORCEPROP 1 LAST BODY_TYPE PLUMBING
J 0
(-3250 4050);
DISPLAY 1.234043 (-3250 4050);
PAINT GREEN (-3250 4050);
DISPLAY INVISIBLE (-3250 4050);
FORCEPROP 1 LAST HDL_TAP TRUE
J 0
(-2925 3975);
DISPLAY 1.234043 (-2925 3975);
PAINT GREEN (-2925 3975);
DISPLAY INVISIBLE (-2925 3975);
FORCEPROP 1 LAST PATH I134
J 0
(-3250 4100);
DISPLAY 0.936170 (-3250 4100);
PAINT GREEN (-3250 4100);
DISPLAY INVISIBLE (-3250 4100);
FORCEADD TAP..6
(-3250 4050);
FORCEPROP 3 LASTPIN (-3200 4050) SIG_NAME M_D_BG<0>
J 0
(-3190 4060);
DISPLAY 0.659574 (-3190 4060);
PAINT MONO (-3190 4060);
DISPLAY INVISIBLE (-3190 4060);
FORCEPROP 1 LASTPIN (-3200 4050) BN 0
J 0
(-3250 4060);
DISPLAY 0.617021 (-3250 4060);
PAINT PINK (-3250 4060);
FORCEPROP 2 LAST CDS_LIB mstr_standard
J 0
(-3250 4050);
DISPLAY 0.787234 (-3250 4050);
PAINT MONO (-3250 4050);
DISPLAY INVISIBLE (-3250 4050);
FORCEPROP 1 LAST BODY_TYPE PLUMBING
J 0
(-3250 4000);
DISPLAY 1.234043 (-3250 4000);
PAINT GREEN (-3250 4000);
DISPLAY INVISIBLE (-3250 4000);
FORCEPROP 1 LAST HDL_TAP TRUE
J 0
(-2925 3925);
DISPLAY 1.234043 (-2925 3925);
PAINT GREEN (-2925 3925);
DISPLAY INVISIBLE (-2925 3925);
FORCEPROP 1 LAST PATH I135
J 0
(-3250 4050);
DISPLAY 0.936170 (-3250 4050);
PAINT GREEN (-3250 4050);
DISPLAY INVISIBLE (-3250 4050);
FORCEADD OFFPAGE..1
(-4000 3750);
FORCEPROP 2 LAST $XR0 26 
J 0
(-4251 3750);
DISPLAY 0.638298 (-4251 3750);
PAINT MONO (-4251 3750);
FORCEPROP 2 LAST $XR1 50 
J 0
(-4341 3750);
DISPLAY 0.638298 (-4341 3750);
PAINT MONO (-4341 3750);
FORCEPROP 2 LAST CDS_LIB mstr_standard
J 0
(-4000 3750);
DISPLAY 0.787234 (-4000 3750);
PAINT MONO (-4000 3750);
DISPLAY INVISIBLE (-4000 3750);
FORCEPROP 1 LAST OFFPAGE TRUE
J 0
(-3675 3625);
DISPLAY 0.936170 (-3675 3625);
PAINT GREEN (-3675 3625);
DISPLAY INVISIBLE (-3675 3625);
FORCEPROP 1 LAST COMMENT_BODY TRUE
J 0
(-3875 3650);
DISPLAY 0.936170 (-3875 3650);
PAINT GREEN (-3875 3650);
DISPLAY INVISIBLE (-3875 3650);
FORCEPROP 2 LAST PATH I136
J 0
(-3950 3825);
DISPLAY 0.787234 (-3950 3825);
PAINT MONO (-3950 3825);
DISPLAY INVISIBLE (-3950 3825);
FORCEADD OFFPAGE..1
(-4000 4150);
FORCEPROP 2 LAST $XR0 26 
J 0
(-4251 4150);
DISPLAY 0.638298 (-4251 4150);
PAINT MONO (-4251 4150);
FORCEPROP 2 LAST $XR1 50 
J 0
(-4341 4150);
DISPLAY 0.638298 (-4341 4150);
PAINT MONO (-4341 4150);
FORCEPROP 2 LAST CDS_LIB mstr_standard
J 0
(-4000 4150);
DISPLAY 0.787234 (-4000 4150);
PAINT MONO (-4000 4150);
DISPLAY INVISIBLE (-4000 4150);
FORCEPROP 1 LAST OFFPAGE TRUE
J 0
(-3675 4025);
DISPLAY 0.936170 (-3675 4025);
PAINT GREEN (-3675 4025);
DISPLAY INVISIBLE (-3675 4025);
FORCEPROP 1 LAST COMMENT_BODY TRUE
J 0
(-3875 4050);
DISPLAY 0.936170 (-3875 4050);
PAINT GREEN (-3875 4050);
DISPLAY INVISIBLE (-3875 4050);
FORCEPROP 2 LAST PATH I137
J 0
(-3950 4225);
DISPLAY 0.787234 (-3950 4225);
PAINT MONO (-3950 4225);
DISPLAY INVISIBLE (-3950 4225);
FORCEADD TAP..6
(-3250 3050);
FORCEPROP 3 LASTPIN (-3200 3050) SIG_NAME M_D_ECC<7>
J 0
(-3190 3060);
DISPLAY 0.659574 (-3190 3060);
PAINT MONO (-3190 3060);
DISPLAY INVISIBLE (-3190 3060);
FORCEPROP 1 LASTPIN (-3200 3050) BN 7
J 0
(-3250 3060);
DISPLAY 0.617021 (-3250 3060);
PAINT PINK (-3250 3060);
FORCEPROP 2 LAST CDS_LIB mstr_standard
J 0
(-3250 3050);
DISPLAY 0.787234 (-3250 3050);
PAINT MONO (-3250 3050);
DISPLAY INVISIBLE (-3250 3050);
FORCEPROP 1 LAST BODY_TYPE PLUMBING
J 0
(-3250 3000);
DISPLAY 1.234043 (-3250 3000);
PAINT GREEN (-3250 3000);
DISPLAY INVISIBLE (-3250 3000);
FORCEPROP 1 LAST HDL_TAP TRUE
J 0
(-2925 2925);
DISPLAY 1.234043 (-2925 2925);
PAINT GREEN (-2925 2925);
DISPLAY INVISIBLE (-2925 2925);
FORCEPROP 1 LAST PATH I138
J 0
(-3250 3050);
DISPLAY 0.936170 (-3250 3050);
PAINT GREEN (-3250 3050);
DISPLAY INVISIBLE (-3250 3050);
FORCEADD TAP..6
(-3250 3100);
FORCEPROP 3 LASTPIN (-3200 3100) SIG_NAME M_D_ECC<6>
J 0
(-3190 3110);
DISPLAY 0.659574 (-3190 3110);
PAINT MONO (-3190 3110);
DISPLAY INVISIBLE (-3190 3110);
FORCEPROP 1 LASTPIN (-3200 3100) BN 6
J 0
(-3250 3110);
DISPLAY 0.617021 (-3250 3110);
PAINT PINK (-3250 3110);
FORCEPROP 2 LAST CDS_LIB mstr_standard
J 0
(-3250 3100);
DISPLAY 0.787234 (-3250 3100);
PAINT MONO (-3250 3100);
DISPLAY INVISIBLE (-3250 3100);
FORCEPROP 1 LAST BODY_TYPE PLUMBING
J 0
(-3250 3050);
DISPLAY 1.234043 (-3250 3050);
PAINT GREEN (-3250 3050);
DISPLAY INVISIBLE (-3250 3050);
FORCEPROP 1 LAST HDL_TAP TRUE
J 0
(-2925 2975);
DISPLAY 1.234043 (-2925 2975);
PAINT GREEN (-2925 2975);
DISPLAY INVISIBLE (-2925 2975);
FORCEPROP 1 LAST PATH I139
J 0
(-3250 3100);
DISPLAY 0.936170 (-3250 3100);
PAINT GREEN (-3250 3100);
DISPLAY INVISIBLE (-3250 3100);
FORCEADD TAP..6
R 2
(650 4600);
FORCEPROP 3 LASTPIN (600 4600) SIG_NAME M_D_DQS_DP<11>
J 0
(610 4610);
DISPLAY 0.659574 (610 4610);
PAINT MONO (610 4610);
DISPLAY INVISIBLE (610 4610);
FORCEPROP 1 LASTPIN (600 4600) BN 11
J 2
(650 4610);
DISPLAY 0.617021 (650 4610);
PAINT PINK (650 4610);
FORCEPROP 2 LAST CDS_LIB mstr_standard
J 0
(650 4600);
DISPLAY 0.787234 (650 4600);
PAINT MONO (650 4600);
DISPLAY INVISIBLE (650 4600);
FORCEPROP 1 LAST BODY_TYPE PLUMBING
J 2
(650 4550);
DISPLAY 1.234043 (650 4550);
PAINT GREEN (650 4550);
DISPLAY INVISIBLE (650 4550);
FORCEPROP 1 LAST HDL_TAP TRUE
J 2
(325 4475);
DISPLAY 1.234043 (325 4475);
PAINT GREEN (325 4475);
DISPLAY INVISIBLE (325 4475);
FORCEPROP 1 LAST PATH I14
J 2
(650 4600);
DISPLAY 0.936170 (650 4600);
PAINT GREEN (650 4600);
DISPLAY INVISIBLE (650 4600);
FORCEADD TAP..6
(-3250 3000);
FORCEPROP 3 LASTPIN (-3200 3000) SIG_NAME M_D_ECC<4>
J 0
(-3190 3010);
DISPLAY 0.659574 (-3190 3010);
PAINT MONO (-3190 3010);
DISPLAY INVISIBLE (-3190 3010);
FORCEPROP 1 LASTPIN (-3200 3000) BN 4
J 0
(-3250 3010);
DISPLAY 0.617021 (-3250 3010);
PAINT PINK (-3250 3010);
FORCEPROP 2 LAST CDS_LIB mstr_standard
J 0
(-3250 3000);
DISPLAY 0.787234 (-3250 3000);
PAINT MONO (-3250 3000);
DISPLAY INVISIBLE (-3250 3000);
FORCEPROP 1 LAST BODY_TYPE PLUMBING
J 0
(-3250 2950);
DISPLAY 1.234043 (-3250 2950);
PAINT GREEN (-3250 2950);
DISPLAY INVISIBLE (-3250 2950);
FORCEPROP 1 LAST HDL_TAP TRUE
J 0
(-2925 2875);
DISPLAY 1.234043 (-2925 2875);
PAINT GREEN (-2925 2875);
DISPLAY INVISIBLE (-2925 2875);
FORCEPROP 1 LAST PATH I140
J 0
(-3250 3000);
DISPLAY 0.936170 (-3250 3000);
PAINT GREEN (-3250 3000);
DISPLAY INVISIBLE (-3250 3000);
FORCEADD TAP..6
(-3250 2950);
FORCEPROP 3 LASTPIN (-3200 2950) SIG_NAME M_D_ECC<5>
J 0
(-3190 2960);
DISPLAY 0.659574 (-3190 2960);
PAINT MONO (-3190 2960);
DISPLAY INVISIBLE (-3190 2960);
FORCEPROP 1 LASTPIN (-3200 2950) BN 5
J 0
(-3250 2960);
DISPLAY 0.617021 (-3250 2960);
PAINT PINK (-3250 2960);
FORCEPROP 2 LAST CDS_LIB mstr_standard
J 0
(-3250 2950);
DISPLAY 0.787234 (-3250 2950);
PAINT MONO (-3250 2950);
DISPLAY INVISIBLE (-3250 2950);
FORCEPROP 1 LAST BODY_TYPE PLUMBING
J 0
(-3250 2900);
DISPLAY 1.234043 (-3250 2900);
PAINT GREEN (-3250 2900);
DISPLAY INVISIBLE (-3250 2900);
FORCEPROP 1 LAST HDL_TAP TRUE
J 0
(-2925 2825);
DISPLAY 1.234043 (-2925 2825);
PAINT GREEN (-2925 2825);
DISPLAY INVISIBLE (-2925 2825);
FORCEPROP 1 LAST PATH I141
J 0
(-3250 2950);
DISPLAY 0.936170 (-3250 2950);
PAINT GREEN (-3250 2950);
DISPLAY INVISIBLE (-3250 2950);
FORCEADD TAP..6
(-3250 2900);
FORCEPROP 3 LASTPIN (-3200 2900) SIG_NAME M_D_ECC<2>
J 0
(-3190 2910);
DISPLAY 0.659574 (-3190 2910);
PAINT MONO (-3190 2910);
DISPLAY INVISIBLE (-3190 2910);
FORCEPROP 1 LASTPIN (-3200 2900) BN 2
J 0
(-3250 2910);
DISPLAY 0.617021 (-3250 2910);
PAINT PINK (-3250 2910);
FORCEPROP 2 LAST CDS_LIB mstr_standard
J 0
(-3250 2900);
DISPLAY 0.787234 (-3250 2900);
PAINT MONO (-3250 2900);
DISPLAY INVISIBLE (-3250 2900);
FORCEPROP 1 LAST BODY_TYPE PLUMBING
J 0
(-3250 2850);
DISPLAY 1.234043 (-3250 2850);
PAINT GREEN (-3250 2850);
DISPLAY INVISIBLE (-3250 2850);
FORCEPROP 1 LAST HDL_TAP TRUE
J 0
(-2925 2775);
DISPLAY 1.234043 (-2925 2775);
PAINT GREEN (-2925 2775);
DISPLAY INVISIBLE (-2925 2775);
FORCEPROP 1 LAST PATH I142
J 0
(-3250 2900);
DISPLAY 0.936170 (-3250 2900);
PAINT GREEN (-3250 2900);
DISPLAY INVISIBLE (-3250 2900);
FORCEADD TAP..6
(-3250 2850);
FORCEPROP 3 LASTPIN (-3200 2850) SIG_NAME M_D_ECC<3>
J 0
(-3190 2860);
DISPLAY 0.659574 (-3190 2860);
PAINT MONO (-3190 2860);
DISPLAY INVISIBLE (-3190 2860);
FORCEPROP 1 LASTPIN (-3200 2850) BN 3
J 0
(-3250 2860);
DISPLAY 0.617021 (-3250 2860);
PAINT PINK (-3250 2860);
FORCEPROP 2 LAST CDS_LIB mstr_standard
J 0
(-3250 2850);
DISPLAY 0.787234 (-3250 2850);
PAINT MONO (-3250 2850);
DISPLAY INVISIBLE (-3250 2850);
FORCEPROP 1 LAST BODY_TYPE PLUMBING
J 0
(-3250 2800);
DISPLAY 1.234043 (-3250 2800);
PAINT GREEN (-3250 2800);
DISPLAY INVISIBLE (-3250 2800);
FORCEPROP 1 LAST HDL_TAP TRUE
J 0
(-2925 2725);
DISPLAY 1.234043 (-2925 2725);
PAINT GREEN (-2925 2725);
DISPLAY INVISIBLE (-2925 2725);
FORCEPROP 1 LAST PATH I143
J 0
(-3250 2850);
DISPLAY 0.936170 (-3250 2850);
PAINT GREEN (-3250 2850);
DISPLAY INVISIBLE (-3250 2850);
FORCEADD TAP..6
(-3250 2800);
FORCEPROP 3 LASTPIN (-3200 2800) SIG_NAME M_D_ECC<0>
J 0
(-3190 2810);
DISPLAY 0.659574 (-3190 2810);
PAINT MONO (-3190 2810);
DISPLAY INVISIBLE (-3190 2810);
FORCEPROP 1 LASTPIN (-3200 2800) BN 0
J 0
(-3250 2810);
DISPLAY 0.617021 (-3250 2810);
PAINT PINK (-3250 2810);
FORCEPROP 2 LAST CDS_LIB mstr_standard
J 0
(-3250 2800);
DISPLAY 0.787234 (-3250 2800);
PAINT MONO (-3250 2800);
DISPLAY INVISIBLE (-3250 2800);
FORCEPROP 1 LAST BODY_TYPE PLUMBING
J 0
(-3250 2750);
DISPLAY 1.234043 (-3250 2750);
PAINT GREEN (-3250 2750);
DISPLAY INVISIBLE (-3250 2750);
FORCEPROP 1 LAST HDL_TAP TRUE
J 0
(-2925 2675);
DISPLAY 1.234043 (-2925 2675);
PAINT GREEN (-2925 2675);
DISPLAY INVISIBLE (-2925 2675);
FORCEPROP 1 LAST PATH I144
J 0
(-3250 2800);
DISPLAY 0.936170 (-3250 2800);
PAINT GREEN (-3250 2800);
DISPLAY INVISIBLE (-3250 2800);
FORCEADD TAP..6
(-3250 2750);
FORCEPROP 3 LASTPIN (-3200 2750) SIG_NAME M_D_ECC<1>
J 0
(-3190 2760);
DISPLAY 0.659574 (-3190 2760);
PAINT MONO (-3190 2760);
DISPLAY INVISIBLE (-3190 2760);
FORCEPROP 1 LASTPIN (-3200 2750) BN 1
J 0
(-3250 2760);
DISPLAY 0.617021 (-3250 2760);
PAINT PINK (-3250 2760);
FORCEPROP 2 LAST CDS_LIB mstr_standard
J 0
(-3250 2750);
DISPLAY 0.787234 (-3250 2750);
PAINT MONO (-3250 2750);
DISPLAY INVISIBLE (-3250 2750);
FORCEPROP 1 LAST BODY_TYPE PLUMBING
J 0
(-3250 2700);
DISPLAY 1.234043 (-3250 2700);
PAINT GREEN (-3250 2700);
DISPLAY INVISIBLE (-3250 2700);
FORCEPROP 1 LAST HDL_TAP TRUE
J 0
(-2925 2625);
DISPLAY 1.234043 (-2925 2625);
PAINT GREEN (-2925 2625);
DISPLAY INVISIBLE (-2925 2625);
FORCEPROP 1 LAST PATH I145
J 0
(-3250 2750);
DISPLAY 0.936170 (-3250 2750);
PAINT GREEN (-3250 2750);
DISPLAY INVISIBLE (-3250 2750);
FORCEADD OFFPAGE..1
(-4000 3100);
FORCEPROP 2 LAST $XR0 26 
J 0
(-4251 3100);
DISPLAY 0.638298 (-4251 3100);
PAINT MONO (-4251 3100);
FORCEPROP 2 LAST $XR1 50 
J 0
(-4341 3100);
DISPLAY 0.638298 (-4341 3100);
PAINT MONO (-4341 3100);
FORCEPROP 2 LAST CDS_LIB mstr_standard
J 0
(-4000 3100);
DISPLAY 0.787234 (-4000 3100);
PAINT MONO (-4000 3100);
DISPLAY INVISIBLE (-4000 3100);
FORCEPROP 1 LAST OFFPAGE TRUE
J 0
(-3675 2975);
DISPLAY 0.936170 (-3675 2975);
PAINT GREEN (-3675 2975);
DISPLAY INVISIBLE (-3675 2975);
FORCEPROP 1 LAST COMMENT_BODY TRUE
J 0
(-3875 3000);
DISPLAY 0.936170 (-3875 3000);
PAINT GREEN (-3875 3000);
DISPLAY INVISIBLE (-3875 3000);
FORCEPROP 2 LAST PATH I146
J 0
(-3950 3175);
DISPLAY 0.787234 (-3950 3175);
PAINT MONO (-3950 3175);
DISPLAY INVISIBLE (-3950 3175);
FORCEADD OFFPAGE..1
(-4000 2450);
FORCEPROP 2 LAST $XR0 26 
J 0
(-4251 2450);
DISPLAY 0.638298 (-4251 2450);
PAINT MONO (-4251 2450);
FORCEPROP 2 LAST $XR1 50 
J 0
(-4341 2450);
DISPLAY 0.638298 (-4341 2450);
PAINT MONO (-4341 2450);
FORCEPROP 2 LAST CDS_LIB mstr_standard
J 0
(-4000 2450);
DISPLAY 0.787234 (-4000 2450);
PAINT MONO (-4000 2450);
DISPLAY INVISIBLE (-4000 2450);
FORCEPROP 1 LAST OFFPAGE TRUE
J 0
(-3675 2325);
DISPLAY 0.936170 (-3675 2325);
PAINT GREEN (-3675 2325);
DISPLAY INVISIBLE (-3675 2325);
FORCEPROP 1 LAST COMMENT_BODY TRUE
J 0
(-3875 2350);
DISPLAY 0.936170 (-3875 2350);
PAINT GREEN (-3875 2350);
DISPLAY INVISIBLE (-3875 2350);
FORCEPROP 2 LAST PATH I147
J 0
(-3950 2525);
DISPLAY 0.787234 (-3950 2525);
PAINT MONO (-3950 2525);
DISPLAY INVISIBLE (-3950 2525);
FORCEADD OFFPAGE..5
(-4025 2500);
FORCEPROP 2 LAST $XR0 50 
J 0
(-4249 2500);
DISPLAY 0.638298 (-4249 2500);
PAINT MONO (-4249 2500);
FORCEPROP 2 LAST $XR1 26 
J 0
(-4339 2500);
DISPLAY 0.638298 (-4339 2500);
PAINT MONO (-4339 2500);
FORCEPROP 2 LAST CDS_LIB mstr_standard
J 0
(-4025 2500);
DISPLAY 0.787234 (-4025 2500);
PAINT MONO (-4025 2500);
DISPLAY INVISIBLE (-4025 2500);
FORCEPROP 1 LAST OFFPAGE TRUE
J 0
(-3700 2375);
DISPLAY 1.404255 (-3700 2375);
PAINT GREEN (-3700 2375);
DISPLAY INVISIBLE (-3700 2375);
FORCEPROP 1 LAST COMMENT_BODY TRUE
J 0
(-3925 2425);
DISPLAY 1.404255 (-3925 2425);
PAINT GREEN (-3925 2425);
DISPLAY INVISIBLE (-3925 2425);
FORCEPROP 2 LAST PATH I148
J 0
(-3975 2575);
DISPLAY 0.787234 (-3975 2575);
PAINT MONO (-3975 2575);
DISPLAY INVISIBLE (-3975 2575);
FORCEADD OFFPAGE..1
(-4000 3050);
FORCEPROP 2 LAST $XR0 21 
J 0
(-4251 3050);
DISPLAY 0.638298 (-4251 3050);
PAINT MONO (-4251 3050);
FORCEPROP 2 LAST $XR1 50 
J 0
(-4341 3050);
DISPLAY 0.638298 (-4341 3050);
PAINT MONO (-4341 3050);
FORCEPROP 2 LAST $XR2 51 
J 0
(-4431 3050);
DISPLAY 0.638298 (-4431 3050);
PAINT MONO (-4431 3050);
FORCEPROP 2 LAST $XR3 52 
J 0
(-4521 3050);
DISPLAY 0.638298 (-4521 3050);
PAINT MONO (-4521 3050);
FORCEPROP 2 LAST $XR4 53 
J 0
(-4611 3050);
DISPLAY 0.638298 (-4611 3050);
PAINT MONO (-4611 3050);
FORCEPROP 2 LAST $XR5 54 
J 0
(-4701 3050);
DISPLAY 0.638298 (-4701 3050);
PAINT MONO (-4701 3050);
FORCEPROP 2 LAST CDS_LIB mstr_standard
J 0
(-4000 3050);
DISPLAY 0.787234 (-4000 3050);
PAINT MONO (-4000 3050);
DISPLAY INVISIBLE (-4000 3050);
FORCEPROP 1 LAST OFFPAGE TRUE
J 0
(-3675 2925);
DISPLAY 0.936170 (-3675 2925);
PAINT GREEN (-3675 2925);
DISPLAY INVISIBLE (-3675 2925);
FORCEPROP 1 LAST COMMENT_BODY TRUE
J 0
(-3875 2950);
DISPLAY 0.936170 (-3875 2950);
PAINT GREEN (-3875 2950);
DISPLAY INVISIBLE (-3875 2950);
FORCEPROP 2 LAST PATH I149
J 0
(-3950 3125);
DISPLAY 0.787234 (-3950 3125);
PAINT MONO (-3950 3125);
DISPLAY INVISIBLE (-3950 3125);
FORCEADD TAP..6
R 2
(650 4700);
FORCEPROP 3 LASTPIN (600 4700) SIG_NAME M_D_DQS_DP<12>
J 0
(610 4710);
DISPLAY 0.659574 (610 4710);
PAINT MONO (610 4710);
DISPLAY INVISIBLE (610 4710);
FORCEPROP 1 LASTPIN (600 4700) BN 12
J 2
(650 4710);
DISPLAY 0.617021 (650 4710);
PAINT PINK (650 4710);
FORCEPROP 2 LAST CDS_LIB mstr_standard
J 0
(650 4700);
DISPLAY 0.787234 (650 4700);
PAINT MONO (650 4700);
DISPLAY INVISIBLE (650 4700);
FORCEPROP 1 LAST BODY_TYPE PLUMBING
J 2
(650 4650);
DISPLAY 1.234043 (650 4650);
PAINT GREEN (650 4650);
DISPLAY INVISIBLE (650 4650);
FORCEPROP 1 LAST HDL_TAP TRUE
J 2
(325 4575);
DISPLAY 1.234043 (325 4575);
PAINT GREEN (325 4575);
DISPLAY INVISIBLE (325 4575);
FORCEPROP 1 LAST PATH I15
J 2
(650 4700);
DISPLAY 0.936170 (650 4700);
PAINT GREEN (650 4700);
DISPLAY INVISIBLE (650 4700);
FORCEADD OFFPAGE..6
(-4000 3150);
FORCEPROP 2 LAST $XR0 26 
J 0
(-4249 3150);
DISPLAY 0.638298 (-4249 3150);
PAINT MONO (-4249 3150);
FORCEPROP 2 LAST $XR1 50 
J 0
(-4339 3150);
DISPLAY 0.638298 (-4339 3150);
PAINT MONO (-4339 3150);
FORCEPROP 2 LAST CDS_LIB mstr_standard
J 0
(-4000 3150);
DISPLAY 0.787234 (-4000 3150);
PAINT MONO (-4000 3150);
DISPLAY INVISIBLE (-4000 3150);
FORCEPROP 1 LAST OFFPAGE TRUE
J 0
(-3675 3025);
DISPLAY 0.936170 (-3675 3025);
PAINT GREEN (-3675 3025);
DISPLAY INVISIBLE (-3675 3025);
FORCEPROP 1 LAST COMMENT_BODY TRUE
J 0
(-3900 3075);
DISPLAY 0.936170 (-3900 3075);
PAINT GREEN (-3900 3075);
DISPLAY INVISIBLE (-3900 3075);
FORCEPROP 2 LAST PATH I150
J 0
(-3950 3225);
DISPLAY 0.787234 (-3950 3225);
PAINT MONO (-3950 3225);
DISPLAY INVISIBLE (-3950 3225);
FORCEADD OFFPAGE..1
(-4800 2000);
FORCEPROP 2 LAST $XR0 98 
J 0
(-5051 2000);
DISPLAY 0.638298 (-5051 2000);
PAINT MONO (-5051 2000);
FORCEPROP 2 LAST $XR1 50 
J 0
(-5141 2000);
DISPLAY 0.638298 (-5141 2000);
PAINT MONO (-5141 2000);
FORCEPROP 2 LAST CDS_LIB mstr_standard
J 0
(-4800 2000);
DISPLAY 0.787234 (-4800 2000);
PAINT MONO (-4800 2000);
DISPLAY INVISIBLE (-4800 2000);
FORCEPROP 1 LAST OFFPAGE TRUE
J 0
(-4475 1875);
DISPLAY 0.936170 (-4475 1875);
PAINT GREEN (-4475 1875);
DISPLAY INVISIBLE (-4475 1875);
FORCEPROP 1 LAST COMMENT_BODY TRUE
J 0
(-4675 1900);
DISPLAY 0.936170 (-4675 1900);
PAINT GREEN (-4675 1900);
DISPLAY INVISIBLE (-4675 1900);
FORCEPROP 2 LAST PATH I151
J 0
(-4750 2075);
DISPLAY 0.787234 (-4750 2075);
PAINT MONO (-4750 2075);
DISPLAY INVISIBLE (-4750 2075);
FORCEADD TAP..6
(-3250 3950);
FORCEPROP 3 LASTPIN (-3200 3950) SIG_NAME M_D_CLK_DP<1>
J 0
(-3190 3960);
DISPLAY 0.659574 (-3190 3960);
PAINT MONO (-3190 3960);
DISPLAY INVISIBLE (-3190 3960);
FORCEPROP 1 LASTPIN (-3200 3950) BN 1
J 0
(-3250 3960);
DISPLAY 0.617021 (-3250 3960);
PAINT PINK (-3250 3960);
FORCEPROP 2 LAST CDS_LIB mstr_standard
J 0
(-3250 3950);
DISPLAY 0.787234 (-3250 3950);
PAINT MONO (-3250 3950);
DISPLAY INVISIBLE (-3250 3950);
FORCEPROP 1 LAST BODY_TYPE PLUMBING
J 0
(-3250 3900);
DISPLAY 1.234043 (-3250 3900);
PAINT GREEN (-3250 3900);
DISPLAY INVISIBLE (-3250 3900);
FORCEPROP 1 LAST HDL_TAP TRUE
J 0
(-2925 3825);
DISPLAY 1.234043 (-2925 3825);
PAINT GREEN (-2925 3825);
DISPLAY INVISIBLE (-2925 3825);
FORCEPROP 1 LAST PATH I152
J 0
(-3250 3950);
DISPLAY 0.936170 (-3250 3950);
PAINT GREEN (-3250 3950);
DISPLAY INVISIBLE (-3250 3950);
FORCEADD TAP..6
(-3250 3850);
FORCEPROP 3 LASTPIN (-3200 3850) SIG_NAME M_D_CLK_DP<0>
J 0
(-3190 3860);
DISPLAY 0.659574 (-3190 3860);
PAINT MONO (-3190 3860);
DISPLAY INVISIBLE (-3190 3860);
FORCEPROP 1 LASTPIN (-3200 3850) BN 0
J 0
(-3250 3860);
DISPLAY 0.617021 (-3250 3860);
PAINT PINK (-3250 3860);
FORCEPROP 2 LAST CDS_LIB mstr_standard
J 0
(-3250 3850);
DISPLAY 0.787234 (-3250 3850);
PAINT MONO (-3250 3850);
DISPLAY INVISIBLE (-3250 3850);
FORCEPROP 1 LAST BODY_TYPE PLUMBING
J 0
(-3250 3800);
DISPLAY 1.234043 (-3250 3800);
PAINT GREEN (-3250 3800);
DISPLAY INVISIBLE (-3250 3800);
FORCEPROP 1 LAST HDL_TAP TRUE
J 0
(-2925 3725);
DISPLAY 1.234043 (-2925 3725);
PAINT GREEN (-2925 3725);
DISPLAY INVISIBLE (-2925 3725);
FORCEPROP 1 LAST PATH I153
J 0
(-3250 3850);
DISPLAY 0.936170 (-3250 3850);
PAINT GREEN (-3250 3850);
DISPLAY INVISIBLE (-3250 3850);
FORCEADD TAP..6
(-3450 3900);
FORCEPROP 3 LASTPIN (-3400 3900) SIG_NAME M_D_CLK_DN<1>
J 0
(-3390 3910);
DISPLAY 0.659574 (-3390 3910);
PAINT MONO (-3390 3910);
DISPLAY INVISIBLE (-3390 3910);
FORCEPROP 1 LASTPIN (-3400 3900) BN 1
J 0
(-3450 3910);
DISPLAY 0.617021 (-3450 3910);
PAINT PINK (-3450 3910);
FORCEPROP 2 LAST CDS_LIB mstr_standard
J 0
(-3450 3900);
DISPLAY 0.787234 (-3450 3900);
PAINT MONO (-3450 3900);
DISPLAY INVISIBLE (-3450 3900);
FORCEPROP 1 LAST BODY_TYPE PLUMBING
J 0
(-3450 3850);
DISPLAY 1.234043 (-3450 3850);
PAINT GREEN (-3450 3850);
DISPLAY INVISIBLE (-3450 3850);
FORCEPROP 1 LAST HDL_TAP TRUE
J 0
(-3125 3775);
DISPLAY 1.234043 (-3125 3775);
PAINT GREEN (-3125 3775);
DISPLAY INVISIBLE (-3125 3775);
FORCEPROP 1 LAST PATH I154
J 0
(-3450 3900);
DISPLAY 0.936170 (-3450 3900);
PAINT GREEN (-3450 3900);
DISPLAY INVISIBLE (-3450 3900);
FORCEADD TAP..6
(-3450 3800);
FORCEPROP 3 LASTPIN (-3400 3800) SIG_NAME M_D_CLK_DN<0>
J 0
(-3390 3810);
DISPLAY 0.659574 (-3390 3810);
PAINT MONO (-3390 3810);
DISPLAY INVISIBLE (-3390 3810);
FORCEPROP 1 LASTPIN (-3400 3800) BN 0
J 0
(-3450 3810);
DISPLAY 0.617021 (-3450 3810);
PAINT PINK (-3450 3810);
FORCEPROP 2 LAST CDS_LIB mstr_standard
J 0
(-3450 3800);
DISPLAY 0.787234 (-3450 3800);
PAINT MONO (-3450 3800);
DISPLAY INVISIBLE (-3450 3800);
FORCEPROP 1 LAST BODY_TYPE PLUMBING
J 0
(-3450 3750);
DISPLAY 1.234043 (-3450 3750);
PAINT GREEN (-3450 3750);
DISPLAY INVISIBLE (-3450 3750);
FORCEPROP 1 LAST HDL_TAP TRUE
J 0
(-3125 3675);
DISPLAY 1.234043 (-3125 3675);
PAINT GREEN (-3125 3675);
DISPLAY INVISIBLE (-3125 3675);
FORCEPROP 1 LAST PATH I155
J 0
(-3450 3800);
DISPLAY 0.936170 (-3450 3800);
PAINT GREEN (-3450 3800);
DISPLAY INVISIBLE (-3450 3800);
FORCEADD OFFPAGE..1
(-4000 3950);
FORCEPROP 2 LAST $XR0 26 
J 0
(-4251 3950);
DISPLAY 0.638298 (-4251 3950);
PAINT MONO (-4251 3950);
FORCEPROP 2 LAST $XR1 50 
J 0
(-4341 3950);
DISPLAY 0.638298 (-4341 3950);
PAINT MONO (-4341 3950);
FORCEPROP 2 LAST CDS_LIB mstr_standard
J 0
(-4000 3950);
DISPLAY 0.787234 (-4000 3950);
PAINT MONO (-4000 3950);
DISPLAY INVISIBLE (-4000 3950);
FORCEPROP 1 LAST OFFPAGE TRUE
J 0
(-3675 3825);
DISPLAY 0.936170 (-3675 3825);
PAINT GREEN (-3675 3825);
DISPLAY INVISIBLE (-3675 3825);
FORCEPROP 1 LAST COMMENT_BODY TRUE
J 0
(-3875 3850);
DISPLAY 0.936170 (-3875 3850);
PAINT GREEN (-3875 3850);
DISPLAY INVISIBLE (-3875 3850);
FORCEPROP 2 LAST PATH I156
J 0
(-3950 4025);
DISPLAY 0.787234 (-3950 4025);
PAINT MONO (-3950 4025);
DISPLAY INVISIBLE (-3950 4025);
FORCEADD OFFPAGE..1
(-4000 4000);
FORCEPROP 2 LAST $XR0 26 
J 0
(-4251 4000);
DISPLAY 0.638298 (-4251 4000);
PAINT MONO (-4251 4000);
FORCEPROP 2 LAST $XR1 50 
J 0
(-4341 4000);
DISPLAY 0.638298 (-4341 4000);
PAINT MONO (-4341 4000);
FORCEPROP 2 LAST CDS_LIB mstr_standard
J 0
(-4000 4000);
DISPLAY 0.787234 (-4000 4000);
PAINT MONO (-4000 4000);
DISPLAY INVISIBLE (-4000 4000);
FORCEPROP 1 LAST OFFPAGE TRUE
J 0
(-3675 3875);
DISPLAY 0.936170 (-3675 3875);
PAINT GREEN (-3675 3875);
DISPLAY INVISIBLE (-3675 3875);
FORCEPROP 1 LAST COMMENT_BODY TRUE
J 0
(-3875 3900);
DISPLAY 0.936170 (-3875 3900);
PAINT GREEN (-3875 3900);
DISPLAY INVISIBLE (-3875 3900);
FORCEPROP 2 LAST PATH I157
J 0
(-3950 4075);
DISPLAY 0.787234 (-3950 4075);
PAINT MONO (-3950 4075);
DISPLAY INVISIBLE (-3950 4075);
FORCEADD TAP..6
(-3250 3650);
FORCEPROP 3 LASTPIN (-3200 3650) SIG_NAME M_D_CS_N<3>
J 0
(-3190 3660);
DISPLAY 0.659574 (-3190 3660);
PAINT MONO (-3190 3660);
DISPLAY INVISIBLE (-3190 3660);
FORCEPROP 1 LASTPIN (-3200 3650) BN 3
J 0
(-3250 3660);
DISPLAY 0.617021 (-3250 3660);
PAINT PINK (-3250 3660);
FORCEPROP 2 LAST CDS_LIB mstr_standard
J 0
(-3250 3650);
DISPLAY 0.787234 (-3250 3650);
PAINT MONO (-3250 3650);
DISPLAY INVISIBLE (-3250 3650);
FORCEPROP 1 LAST BODY_TYPE PLUMBING
J 0
(-3250 3600);
DISPLAY 1.234043 (-3250 3600);
PAINT GREEN (-3250 3600);
DISPLAY INVISIBLE (-3250 3600);
FORCEPROP 1 LAST HDL_TAP TRUE
J 0
(-2925 3525);
DISPLAY 1.234043 (-2925 3525);
PAINT GREEN (-2925 3525);
DISPLAY INVISIBLE (-2925 3525);
FORCEPROP 1 LAST PATH I158
J 0
(-3250 3650);
DISPLAY 0.936170 (-3250 3650);
PAINT GREEN (-3250 3650);
DISPLAY INVISIBLE (-3250 3650);
FORCEADD TAP..6
(-3250 3600);
FORCEPROP 3 LASTPIN (-3200 3600) SIG_NAME M_D_CS_N<2>
J 0
(-3190 3610);
DISPLAY 0.659574 (-3190 3610);
PAINT MONO (-3190 3610);
DISPLAY INVISIBLE (-3190 3610);
FORCEPROP 1 LASTPIN (-3200 3600) BN 2
J 0
(-3250 3610);
DISPLAY 0.617021 (-3250 3610);
PAINT PINK (-3250 3610);
FORCEPROP 2 LAST CDS_LIB mstr_standard
J 0
(-3250 3600);
DISPLAY 0.787234 (-3250 3600);
PAINT MONO (-3250 3600);
DISPLAY INVISIBLE (-3250 3600);
FORCEPROP 1 LAST BODY_TYPE PLUMBING
J 0
(-3250 3550);
DISPLAY 1.234043 (-3250 3550);
PAINT GREEN (-3250 3550);
DISPLAY INVISIBLE (-3250 3550);
FORCEPROP 1 LAST HDL_TAP TRUE
J 0
(-2925 3475);
DISPLAY 1.234043 (-2925 3475);
PAINT GREEN (-2925 3475);
DISPLAY INVISIBLE (-2925 3475);
FORCEPROP 1 LAST PATH I159
J 0
(-3250 3600);
DISPLAY 0.936170 (-3250 3600);
PAINT GREEN (-3250 3600);
DISPLAY INVISIBLE (-3250 3600);
FORCEADD PVDDQ_DEF..1
(-1225 2475);
FORCEPROP 3 LASTPIN (-1225 2425) SIG_NAME PVDDQ_DEF\g
J 0
(-1215 2435);
DISPLAY 0.659574 (-1215 2435);
PAINT MONO (-1215 2435);
DISPLAY INVISIBLE (-1215 2435);
FORCEPROP 1 LAST VOLTAGE 1.2V
J 0
(-1270 2432);
DISPLAY 0.340426 (-1270 2432);
PAINT SKYBLUE (-1270 2432);
DISPLAY INVISIBLE (-1270 2432);
FORCEPROP 2 LAST BOM_COST MEM
J 0
(-1225 2480);
PAINT ORANGE (-1225 2480);
DISPLAY INVISIBLE (-1225 2480);
FORCEPROP 2 LAST CDS_LIB mstr_symbols
J 0
(-1225 2475);
PAINT ORANGE (-1225 2475);
DISPLAY INVISIBLE (-1225 2475);
FORCEPROP 1 LAST BODY_TYPE PLUMBING
J 0
(-1270 2432);
DISPLAY 0.340426 (-1270 2432);
PAINT GREEN (-1270 2432);
DISPLAY INVISIBLE (-1270 2432);
FORCEPROP 1 LAST PATH I16
J 0
(-1175 2500);
DISPLAY 0.872340 (-1175 2500);
PAINT AQUA (-1175 2500);
DISPLAY INVISIBLE (-1175 2500);
FORCEPROP 2 LAST ROOM DDR4_CH_B
J 0
(-1225 2575);
DISPLAY 0.787234 (-1225 2575);
PAINT ORANGE (-1225 2575);
DISPLAY INVISIBLE (-1225 2575);
FORCEPROP 1 LAST HDL_POWER PVDDQ_DEF
J 1
(-1225 2525);
DISPLAY 0.872340 (-1225 2525);
PAINT GREEN (-1225 2525);
DISPLAY INVISIBLE (-1225 2525);
FORCEADD TAP..6
(-3250 3550);
FORCEPROP 3 LASTPIN (-3200 3550) SIG_NAME M_D_CS_N<1>
J 0
(-3190 3560);
DISPLAY 0.659574 (-3190 3560);
PAINT MONO (-3190 3560);
DISPLAY INVISIBLE (-3190 3560);
FORCEPROP 1 LASTPIN (-3200 3550) BN 1
J 0
(-3250 3560);
DISPLAY 0.617021 (-3250 3560);
PAINT PINK (-3250 3560);
FORCEPROP 2 LAST CDS_LIB mstr_standard
J 0
(-3250 3550);
DISPLAY 0.787234 (-3250 3550);
PAINT MONO (-3250 3550);
DISPLAY INVISIBLE (-3250 3550);
FORCEPROP 1 LAST BODY_TYPE PLUMBING
J 0
(-3250 3500);
DISPLAY 1.234043 (-3250 3500);
PAINT GREEN (-3250 3500);
DISPLAY INVISIBLE (-3250 3500);
FORCEPROP 1 LAST HDL_TAP TRUE
J 0
(-2925 3425);
DISPLAY 1.234043 (-2925 3425);
PAINT GREEN (-2925 3425);
DISPLAY INVISIBLE (-2925 3425);
FORCEPROP 1 LAST PATH I160
J 0
(-3250 3550);
DISPLAY 0.936170 (-3250 3550);
PAINT GREEN (-3250 3550);
DISPLAY INVISIBLE (-3250 3550);
FORCEADD TAP..6
(-3250 3500);
FORCEPROP 3 LASTPIN (-3200 3500) SIG_NAME M_D_CS_N<0>
J 0
(-3190 3510);
DISPLAY 0.659574 (-3190 3510);
PAINT MONO (-3190 3510);
DISPLAY INVISIBLE (-3190 3510);
FORCEPROP 1 LASTPIN (-3200 3500) BN 0
J 0
(-3250 3510);
DISPLAY 0.617021 (-3250 3510);
PAINT PINK (-3250 3510);
FORCEPROP 2 LAST CDS_LIB mstr_standard
J 0
(-3250 3500);
DISPLAY 0.787234 (-3250 3500);
PAINT MONO (-3250 3500);
DISPLAY INVISIBLE (-3250 3500);
FORCEPROP 1 LAST BODY_TYPE PLUMBING
J 0
(-3250 3450);
DISPLAY 1.234043 (-3250 3450);
PAINT GREEN (-3250 3450);
DISPLAY INVISIBLE (-3250 3450);
FORCEPROP 1 LAST HDL_TAP TRUE
J 0
(-2925 3375);
DISPLAY 1.234043 (-2925 3375);
PAINT GREEN (-2925 3375);
DISPLAY INVISIBLE (-2925 3375);
FORCEPROP 1 LAST PATH I161
J 0
(-3250 3500);
DISPLAY 0.936170 (-3250 3500);
PAINT GREEN (-3250 3500);
DISPLAY INVISIBLE (-3250 3500);
FORCEADD TAP..6
(-3250 3400);
FORCEPROP 3 LASTPIN (-3200 3400) SIG_NAME M_D_CKE<1>
J 0
(-3190 3410);
DISPLAY 0.659574 (-3190 3410);
PAINT MONO (-3190 3410);
DISPLAY INVISIBLE (-3190 3410);
FORCEPROP 1 LASTPIN (-3200 3400) BN 1
J 0
(-3250 3410);
DISPLAY 0.617021 (-3250 3410);
PAINT PINK (-3250 3410);
FORCEPROP 2 LAST CDS_LIB mstr_standard
J 0
(-3250 3400);
DISPLAY 0.787234 (-3250 3400);
PAINT MONO (-3250 3400);
DISPLAY INVISIBLE (-3250 3400);
FORCEPROP 1 LAST BODY_TYPE PLUMBING
J 0
(-3250 3350);
DISPLAY 1.234043 (-3250 3350);
PAINT GREEN (-3250 3350);
DISPLAY INVISIBLE (-3250 3350);
FORCEPROP 1 LAST HDL_TAP TRUE
J 0
(-2925 3275);
DISPLAY 1.234043 (-2925 3275);
PAINT GREEN (-2925 3275);
DISPLAY INVISIBLE (-2925 3275);
FORCEPROP 1 LAST PATH I162
J 0
(-3250 3400);
DISPLAY 0.936170 (-3250 3400);
PAINT GREEN (-3250 3400);
DISPLAY INVISIBLE (-3250 3400);
FORCEADD TAP..6
(-3250 3350);
FORCEPROP 3 LASTPIN (-3200 3350) SIG_NAME M_D_CKE<0>
J 0
(-3190 3360);
DISPLAY 0.659574 (-3190 3360);
PAINT MONO (-3190 3360);
DISPLAY INVISIBLE (-3190 3360);
FORCEPROP 1 LASTPIN (-3200 3350) BN 0
J 0
(-3250 3360);
DISPLAY 0.617021 (-3250 3360);
PAINT PINK (-3250 3360);
FORCEPROP 2 LAST CDS_LIB mstr_standard
J 0
(-3250 3350);
DISPLAY 0.787234 (-3250 3350);
PAINT MONO (-3250 3350);
DISPLAY INVISIBLE (-3250 3350);
FORCEPROP 1 LAST BODY_TYPE PLUMBING
J 0
(-3250 3300);
DISPLAY 1.234043 (-3250 3300);
PAINT GREEN (-3250 3300);
DISPLAY INVISIBLE (-3250 3300);
FORCEPROP 1 LAST HDL_TAP TRUE
J 0
(-2925 3225);
DISPLAY 1.234043 (-2925 3225);
PAINT GREEN (-2925 3225);
DISPLAY INVISIBLE (-2925 3225);
FORCEPROP 1 LAST PATH I163
J 0
(-3250 3350);
DISPLAY 0.936170 (-3250 3350);
PAINT GREEN (-3250 3350);
DISPLAY INVISIBLE (-3250 3350);
FORCEADD OFFPAGE..1
(-4000 3700);
FORCEPROP 2 LAST $XR0 26 
J 0
(-4251 3700);
DISPLAY 0.638298 (-4251 3700);
PAINT MONO (-4251 3700);
FORCEPROP 2 LAST $XR1 50 
J 0
(-4341 3700);
DISPLAY 0.638298 (-4341 3700);
PAINT MONO (-4341 3700);
FORCEPROP 2 LAST CDS_LIB mstr_standard
J 0
(-4000 3700);
DISPLAY 0.787234 (-4000 3700);
PAINT MONO (-4000 3700);
DISPLAY INVISIBLE (-4000 3700);
FORCEPROP 1 LAST OFFPAGE TRUE
J 0
(-3675 3575);
DISPLAY 0.936170 (-3675 3575);
PAINT GREEN (-3675 3575);
DISPLAY INVISIBLE (-3675 3575);
FORCEPROP 1 LAST COMMENT_BODY TRUE
J 0
(-3875 3600);
DISPLAY 0.936170 (-3875 3600);
PAINT GREEN (-3875 3600);
DISPLAY INVISIBLE (-3875 3600);
FORCEPROP 2 LAST PATH I164
J 0
(-3950 3775);
DISPLAY 0.787234 (-3950 3775);
PAINT MONO (-3950 3775);
DISPLAY INVISIBLE (-3950 3775);
FORCEADD OFFPAGE..1
(-4000 3300);
FORCEPROP 2 LAST $XR0 26 
J 0
(-4251 3300);
DISPLAY 0.638298 (-4251 3300);
PAINT MONO (-4251 3300);
FORCEPROP 2 LAST $XR1 50 
J 0
(-4341 3300);
DISPLAY 0.638298 (-4341 3300);
PAINT MONO (-4341 3300);
FORCEPROP 2 LAST CDS_LIB mstr_standard
J 0
(-4000 3300);
DISPLAY 0.787234 (-4000 3300);
PAINT MONO (-4000 3300);
DISPLAY INVISIBLE (-4000 3300);
FORCEPROP 1 LAST OFFPAGE TRUE
J 0
(-3675 3175);
DISPLAY 0.936170 (-3675 3175);
PAINT GREEN (-3675 3175);
DISPLAY INVISIBLE (-3675 3175);
FORCEPROP 1 LAST COMMENT_BODY TRUE
J 0
(-3875 3200);
DISPLAY 0.936170 (-3875 3200);
PAINT GREEN (-3875 3200);
DISPLAY INVISIBLE (-3875 3200);
FORCEPROP 2 LAST PATH I165
J 0
(-3950 3375);
DISPLAY 0.787234 (-3950 3375);
PAINT MONO (-3950 3375);
DISPLAY INVISIBLE (-3950 3375);
FORCEADD OFFPAGE..1
(-4000 3450);
FORCEPROP 2 LAST $XR0 26 
J 0
(-4251 3450);
DISPLAY 0.638298 (-4251 3450);
PAINT MONO (-4251 3450);
FORCEPROP 2 LAST $XR1 50 
J 0
(-4341 3450);
DISPLAY 0.638298 (-4341 3450);
PAINT MONO (-4341 3450);
FORCEPROP 2 LAST CDS_LIB mstr_standard
J 0
(-4000 3450);
DISPLAY 0.787234 (-4000 3450);
PAINT MONO (-4000 3450);
DISPLAY INVISIBLE (-4000 3450);
FORCEPROP 1 LAST OFFPAGE TRUE
J 0
(-3675 3325);
DISPLAY 0.936170 (-3675 3325);
PAINT GREEN (-3675 3325);
DISPLAY INVISIBLE (-3675 3325);
FORCEPROP 1 LAST COMMENT_BODY TRUE
J 0
(-3875 3350);
DISPLAY 0.936170 (-3875 3350);
PAINT GREEN (-3875 3350);
DISPLAY INVISIBLE (-3875 3350);
FORCEPROP 2 LAST PATH I166
J 0
(-3950 3525);
DISPLAY 0.787234 (-3950 3525);
PAINT MONO (-3950 3525);
DISPLAY INVISIBLE (-3950 3525);
FORCEADD TAP..6
(-3250 3250);
FORCEPROP 3 LASTPIN (-3200 3250) SIG_NAME M_D_ODT<1>
J 0
(-3190 3260);
DISPLAY 0.659574 (-3190 3260);
PAINT MONO (-3190 3260);
DISPLAY INVISIBLE (-3190 3260);
FORCEPROP 1 LASTPIN (-3200 3250) BN 1
J 0
(-3250 3260);
DISPLAY 0.617021 (-3250 3260);
PAINT PINK (-3250 3260);
FORCEPROP 2 LAST CDS_LIB mstr_standard
J 0
(-3250 3250);
DISPLAY 0.787234 (-3250 3250);
PAINT MONO (-3250 3250);
DISPLAY INVISIBLE (-3250 3250);
FORCEPROP 1 LAST BODY_TYPE PLUMBING
J 0
(-3250 3200);
DISPLAY 1.234043 (-3250 3200);
PAINT GREEN (-3250 3200);
DISPLAY INVISIBLE (-3250 3200);
FORCEPROP 1 LAST HDL_TAP TRUE
J 0
(-2925 3125);
DISPLAY 1.234043 (-2925 3125);
PAINT GREEN (-2925 3125);
DISPLAY INVISIBLE (-2925 3125);
FORCEPROP 1 LAST PATH I167
J 0
(-3250 3250);
DISPLAY 0.936170 (-3250 3250);
PAINT GREEN (-3250 3250);
DISPLAY INVISIBLE (-3250 3250);
FORCEADD TAP..6
(-3250 3200);
FORCEPROP 3 LASTPIN (-3200 3200) SIG_NAME M_D_ODT<0>
J 0
(-3190 3210);
DISPLAY 0.659574 (-3190 3210);
PAINT MONO (-3190 3210);
DISPLAY INVISIBLE (-3190 3210);
FORCEPROP 1 LASTPIN (-3200 3200) BN 0
J 0
(-3250 3210);
DISPLAY 0.617021 (-3250 3210);
PAINT PINK (-3250 3210);
FORCEPROP 2 LAST CDS_LIB mstr_standard
J 0
(-3250 3200);
DISPLAY 0.787234 (-3250 3200);
PAINT MONO (-3250 3200);
DISPLAY INVISIBLE (-3250 3200);
FORCEPROP 1 LAST BODY_TYPE PLUMBING
J 0
(-3250 3150);
DISPLAY 1.234043 (-3250 3150);
PAINT GREEN (-3250 3150);
DISPLAY INVISIBLE (-3250 3150);
FORCEPROP 1 LAST HDL_TAP TRUE
J 0
(-2925 3075);
DISPLAY 1.234043 (-2925 3075);
PAINT GREEN (-2925 3075);
DISPLAY INVISIBLE (-2925 3075);
FORCEPROP 1 LAST PATH I168
J 0
(-3250 3200);
DISPLAY 0.936170 (-3250 3200);
PAINT GREEN (-3250 3200);
DISPLAY INVISIBLE (-3250 3200);
FORCEADD SCONN288_H44441004..4
(-50 1950);
FORCEPROP 1 LAST LOCATION J4B1
J 0
(-500 3050);
DISPLAY 0.617021 (-500 3050);
PAINT AQUA (-500 3050);
FORCEPROP 1 LAST PART_NUMBER H44441-004
J 0
(-500 900);
DISPLAY 0.617021 (-500 900);
PAINT BLUE (-500 900);
FORCEPROP 1 LAST MATERIAL SCONN
J 0
(-500 3000);
DISPLAY 0.617021 (-500 3000);
PAINT SKYBLUE (-500 3000);
FORCEPROP 2 LASTPIN (-550 2500) $PN 77
J 2
(-560 2510);
DISPLAY 0.617021 (-560 2510);
PAINT ORANGE (-560 2510);
FORCEPROP 2 LASTPIN (-550 2450) $PN 221
J 2
(-560 2460);
DISPLAY 0.617021 (-560 2460);
PAINT ORANGE (-560 2460);
FORCEPROP 2 LASTPIN (-550 2800) $PN 142
J 2
(-560 2810);
DISPLAY 0.617021 (-560 2810);
PAINT ORANGE (-560 2810);
FORCEPROP 2 LASTPIN (-550 2750) $PN 143
J 2
(-560 2760);
DISPLAY 0.617021 (-560 2760);
PAINT ORANGE (-560 2760);
FORCEPROP 2 LASTPIN (-550 2700) $PN 288
J 2
(-560 2710);
DISPLAY 0.617021 (-560 2710);
PAINT ORANGE (-560 2710);
FORCEPROP 2 LASTPIN (-550 2650) $PN 286
J 2
(-560 2660);
DISPLAY 0.617021 (-560 2660);
PAINT ORANGE (-560 2660);
FORCEPROP 2 LASTPIN (-550 2600) $PN 287
J 2
(-560 2610);
DISPLAY 0.617021 (-560 2610);
PAINT ORANGE (-560 2610);
FORCEPROP 2 LASTPIN (-550 2350) $PN 59
J 2
(-560 2360);
DISPLAY 0.617021 (-560 2360);
PAINT ORANGE (-560 2360);
FORCEPROP 2 LASTPIN (-550 2300) $PN 61
J 2
(-560 2310);
DISPLAY 0.617021 (-560 2310);
PAINT ORANGE (-560 2310);
FORCEPROP 2 LASTPIN (-550 2250) $PN 64
J 2
(-560 2260);
DISPLAY 0.617021 (-560 2260);
PAINT ORANGE (-560 2260);
FORCEPROP 2 LASTPIN (-550 2200) $PN 67
J 2
(-560 2210);
DISPLAY 0.617021 (-560 2210);
PAINT ORANGE (-560 2210);
FORCEPROP 2 LASTPIN (-550 2150) $PN 70
J 2
(-560 2160);
DISPLAY 0.617021 (-560 2160);
PAINT ORANGE (-560 2160);
FORCEPROP 2 LASTPIN (-550 2100) $PN 73
J 2
(-560 2110);
DISPLAY 0.617021 (-560 2110);
PAINT ORANGE (-560 2110);
FORCEPROP 2 LASTPIN (-550 2050) $PN 76
J 2
(-560 2060);
DISPLAY 0.617021 (-560 2060);
PAINT ORANGE (-560 2060);
FORCEPROP 2 LASTPIN (-550 2000) $PN 80
J 2
(-560 2010);
DISPLAY 0.617021 (-560 2010);
PAINT ORANGE (-560 2010);
FORCEPROP 2 LASTPIN (-550 1950) $PN 83
J 2
(-560 1960);
DISPLAY 0.617021 (-560 1960);
PAINT ORANGE (-560 1960);
FORCEPROP 2 LASTPIN (-550 1900) $PN 85
J 2
(-560 1910);
DISPLAY 0.617021 (-560 1910);
PAINT ORANGE (-560 1910);
FORCEPROP 2 LASTPIN (-550 1850) $PN 88
J 2
(-560 1860);
DISPLAY 0.617021 (-560 1860);
PAINT ORANGE (-560 1860);
FORCEPROP 2 LASTPIN (-550 1800) $PN 90
J 2
(-560 1810);
DISPLAY 0.617021 (-560 1810);
PAINT ORANGE (-560 1810);
FORCEPROP 2 LASTPIN (-550 1750) $PN 92
J 2
(-560 1760);
DISPLAY 0.617021 (-560 1760);
PAINT ORANGE (-560 1760);
FORCEPROP 2 LASTPIN (-550 1700) $PN 204
J 2
(-560 1710);
DISPLAY 0.617021 (-560 1710);
PAINT ORANGE (-560 1710);
FORCEPROP 2 LASTPIN (-550 1650) $PN 206
J 2
(-560 1660);
DISPLAY 0.617021 (-560 1660);
PAINT ORANGE (-560 1660);
FORCEPROP 2 LASTPIN (-550 1600) $PN 209
J 2
(-560 1610);
DISPLAY 0.617021 (-560 1610);
PAINT ORANGE (-560 1610);
FORCEPROP 2 LASTPIN (-550 1550) $PN 212
J 2
(-560 1560);
DISPLAY 0.617021 (-560 1560);
PAINT ORANGE (-560 1560);
FORCEPROP 2 LASTPIN (-550 1500) $PN 215
J 2
(-560 1510);
DISPLAY 0.617021 (-560 1510);
PAINT ORANGE (-560 1510);
FORCEPROP 2 LASTPIN (-550 1450) $PN 217
J 2
(-560 1460);
DISPLAY 0.617021 (-560 1460);
PAINT ORANGE (-560 1460);
FORCEPROP 2 LASTPIN (-550 1400) $PN 220
J 2
(-560 1410);
DISPLAY 0.617021 (-560 1410);
PAINT ORANGE (-560 1410);
FORCEPROP 2 LASTPIN (-550 1350) $PN 223
J 2
(-560 1360);
DISPLAY 0.617021 (-560 1360);
PAINT ORANGE (-560 1360);
FORCEPROP 2 LASTPIN (-550 1300) $PN 226
J 2
(-560 1310);
DISPLAY 0.617021 (-560 1310);
PAINT ORANGE (-560 1310);
FORCEPROP 2 LASTPIN (-550 1250) $PN 229
J 2
(-560 1260);
DISPLAY 0.617021 (-560 1260);
PAINT ORANGE (-560 1260);
FORCEPROP 2 LASTPIN (-550 1200) $PN 231
J 2
(-560 1210);
DISPLAY 0.617021 (-560 1210);
PAINT ORANGE (-560 1210);
FORCEPROP 2 LASTPIN (-550 1150) $PN 233
J 2
(-560 1160);
DISPLAY 0.617021 (-560 1160);
PAINT ORANGE (-560 1160);
FORCEPROP 2 LASTPIN (-550 1100) $PN 236
J 2
(-560 1110);
DISPLAY 0.617021 (-560 1110);
PAINT ORANGE (-560 1110);
FORCEPROP 2 LASTPIN (450 2800) $PN 1
J 0
(460 2810);
DISPLAY 0.617021 (460 2810);
PAINT ORANGE (460 2810);
FORCEPROP 2 LASTPIN (450 2750) $PN 145
J 0
(460 2760);
DISPLAY 0.617021 (460 2760);
PAINT ORANGE (460 2760);
FORCEPROP 1 LAST PACK_TYPE PIP
J 0
(-500 3100);
PAINT SKYBLUE (-500 3100);
DISPLAY INVISIBLE (-500 3100);
FORCEPROP 2 LAST BOM_COST MEM
J 0
(-50 1950);
PAINT ORANGE (-50 1950);
DISPLAY INVISIBLE (-50 1950);
FORCEPROP 2 LAST CDS_LIB mstr_sconn
J 0
(-50 1950);
PAINT ORANGE (-50 1950);
DISPLAY INVISIBLE (-50 1950);
FORCEPROP 2 LAST SEC_TYPE PIP
J 0
(-500 3100);
DISPLAY 1.021277 (-500 3100);
PAINT ORANGE (-500 3100);
DISPLAY INVISIBLE (-500 3100);
FORCEPROP 2 LAST SEC 4
J 0
(-500 3100);
DISPLAY 0.680851 (-500 3100);
PAINT MONO (-500 3100);
DISPLAY INVISIBLE (-500 3100);
FORCEPROP 2 LAST CDS_LOCATION J4B1
J 0
(-500 3050);
DISPLAY 0.617021 (-500 3050);
PAINT AQUA (-500 3050);
DISPLAY INVISIBLE (-500 3050);
FORCEPROP 1 LAST PATH I169
J 0
(-50 3000);
PAINT GREEN (-50 3000);
DISPLAY INVISIBLE (-50 3000);
FORCEPROP 2 LAST ROOM DDR4_CH_D
J 0
(-50 1950);
PAINT ORANGE (-50 1950);
DISPLAY INVISIBLE (-50 1950);
FORCEADD PVTT_DEF..1
(-925 2650);
FORCEPROP 3 LASTPIN (-925 2600) SIG_NAME PVTT_DEF\g
J 0
(-915 2610);
DISPLAY 0.659574 (-915 2610);
PAINT MONO (-915 2610);
DISPLAY INVISIBLE (-915 2610);
FORCEPROP 1 LAST VOLTAGE 0.6V
J 0
(-970 2607);
DISPLAY 0.340426 (-970 2607);
PAINT SKYBLUE (-970 2607);
DISPLAY INVISIBLE (-970 2607);
FORCEPROP 2 LAST BOM_COST MEM
J 0
(-925 2655);
PAINT ORANGE (-925 2655);
DISPLAY INVISIBLE (-925 2655);
FORCEPROP 2 LAST CDS_LIB mstr_symbols
J 0
(-925 2650);
PAINT ORANGE (-925 2650);
DISPLAY INVISIBLE (-925 2650);
FORCEPROP 1 LAST BODY_TYPE PLUMBING
J 0
(-970 2607);
DISPLAY 0.340426 (-970 2607);
PAINT GREEN (-970 2607);
DISPLAY INVISIBLE (-970 2607);
FORCEPROP 1 LAST PATH I170
J 0
(-875 2675);
DISPLAY 0.872340 (-875 2675);
PAINT AQUA (-875 2675);
DISPLAY INVISIBLE (-875 2675);
FORCEPROP 2 LAST ROOM DDR4_CH_B
J 0
(-925 2750);
DISPLAY 0.787234 (-925 2750);
PAINT ORANGE (-925 2750);
DISPLAY INVISIBLE (-925 2750);
FORCEPROP 1 LAST HDL_POWER PVTT_DEF
J 1
(-925 2700);
DISPLAY 0.872340 (-925 2700);
PAINT GREEN (-925 2700);
DISPLAY INVISIBLE (-925 2700);
FORCEADD GND..1
R 2
(2500 1150);
FORCEPROP 3 LASTPIN (2500 1200) SIG_NAME GND\g
J 0
(2510 1210);
DISPLAY 0.659574 (2510 1210);
PAINT MONO (2510 1210);
DISPLAY INVISIBLE (2510 1210);
FORCEPROP 1 LAST VOLTAGE 0
J 0
(2500 1150);
PAINT SKYBLUE (2500 1150);
DISPLAY INVISIBLE (2500 1150);
FORCEPROP 1 LAST SIZE 1B
J 2
(2425 1100);
DISPLAY 1.170213 (2425 1100);
PAINT GREEN (2425 1100);
DISPLAY INVISIBLE (2425 1100);
FORCEPROP 2 LAST CDS_LIB mstr_symbols
J 0
(2500 1150);
DISPLAY 0.787234 (2500 1150);
PAINT MONO (2500 1150);
DISPLAY INVISIBLE (2500 1150);
FORCEPROP 2 LAST BOM_COST MEM
J 0
(2500 1155);
PAINT ORANGE (2500 1155);
DISPLAY INVISIBLE (2500 1155);
FORCEPROP 1 LAST BODY_TYPE PLUMBING
J 2
(2545 1107);
DISPLAY 0.340426 (2545 1107);
PAINT GREEN (2545 1107);
DISPLAY INVISIBLE (2545 1107);
FORCEPROP 1 LAST PATH I171
J 2
(2425 1150);
DISPLAY 1.404255 (2425 1150);
PAINT GREEN (2425 1150);
DISPLAY INVISIBLE (2425 1150);
FORCEPROP 2 LAST ROOM DDR4_CH_B
J 0
(2500 1155);
PAINT ORANGE (2500 1155);
DISPLAY INVISIBLE (2500 1155);
FORCEPROP 1 LAST HDL_POWER GND
J 2
(2500 1300);
DISPLAY 0.553191 (2500 1300);
PAINT GREEN (2500 1300);
DISPLAY INVISIBLE (2500 1300);
FORCEADD OFFPAGE..6
(-3850 2150);
FORCEPROP 2 LAST $XR0 50 
J 0
(-4099 2150);
DISPLAY 0.638298 (-4099 2150);
PAINT MONO (-4099 2150);
FORCEPROP 2 LAST $XR1 51 
J 0
(-4189 2150);
DISPLAY 0.638298 (-4189 2150);
PAINT MONO (-4189 2150);
FORCEPROP 2 LAST $XR2 52 
J 0
(-4279 2150);
DISPLAY 0.638298 (-4279 2150);
PAINT MONO (-4279 2150);
FORCEPROP 2 LAST $XR3 53 
J 0
(-4369 2150);
DISPLAY 0.638298 (-4369 2150);
PAINT MONO (-4369 2150);
FORCEPROP 2 LAST $XR4 54 
J 0
(-4459 2150);
DISPLAY 0.638298 (-4459 2150);
PAINT MONO (-4459 2150);
FORCEPROP 2 LAST $XR5 99 
J 0
(-4549 2150);
DISPLAY 0.638298 (-4549 2150);
PAINT MONO (-4549 2150);
FORCEPROP 2 LASTPIN (-3800 2150) SIG_NAME SMB_DDR_DEF_VPP_SDA
J 0
(-3760 2160);
DISPLAY 0.617021 (-3760 2160);
PAINT ORANGE (-3760 2160);
FORCEPROP 2 LAST CDS_LIB mstr_standard
J 0
(-3850 2150);
DISPLAY 0.787234 (-3850 2150);
PAINT MONO (-3850 2150);
DISPLAY INVISIBLE (-3850 2150);
FORCEPROP 1 LAST OFFPAGE TRUE
J 0
(-3525 2025);
DISPLAY 0.936170 (-3525 2025);
PAINT GREEN (-3525 2025);
DISPLAY INVISIBLE (-3525 2025);
FORCEPROP 1 LAST COMMENT_BODY TRUE
J 0
(-3750 2075);
DISPLAY 0.936170 (-3750 2075);
PAINT GREEN (-3750 2075);
DISPLAY INVISIBLE (-3750 2075);
FORCEPROP 2 LAST PATH I174
J 0
(-4150 2200);
DISPLAY 0.787234 (-4150 2200);
PAINT ORANGE (-4150 2200);
DISPLAY INVISIBLE (-4150 2200);
FORCEADD OFFPAGE..1
(-3850 2100);
FORCEPROP 2 LAST $XR0 99 
J 0
(-4101 2100);
DISPLAY 0.638298 (-4101 2100);
PAINT MONO (-4101 2100);
FORCEPROP 2 LAST $XR1 50 
J 0
(-4191 2100);
DISPLAY 0.638298 (-4191 2100);
PAINT MONO (-4191 2100);
FORCEPROP 2 LAST $XR2 51 
J 0
(-4281 2100);
DISPLAY 0.638298 (-4281 2100);
PAINT MONO (-4281 2100);
FORCEPROP 2 LAST $XR3 52 
J 0
(-4371 2100);
DISPLAY 0.638298 (-4371 2100);
PAINT MONO (-4371 2100);
FORCEPROP 2 LAST $XR4 53 
J 0
(-4461 2100);
DISPLAY 0.638298 (-4461 2100);
PAINT MONO (-4461 2100);
FORCEPROP 2 LAST $XR5 54 
J 0
(-4551 2100);
DISPLAY 0.638298 (-4551 2100);
PAINT MONO (-4551 2100);
FORCEPROP 2 LAST CDS_LIB mstr_standard
J 0
(-3850 2100);
DISPLAY 0.787234 (-3850 2100);
PAINT MONO (-3850 2100);
DISPLAY INVISIBLE (-3850 2100);
FORCEPROP 1 LAST OFFPAGE TRUE
J 0
(-3525 1975);
DISPLAY 0.936170 (-3525 1975);
PAINT GREEN (-3525 1975);
DISPLAY INVISIBLE (-3525 1975);
FORCEPROP 1 LAST COMMENT_BODY TRUE
J 0
(-3725 2000);
DISPLAY 0.936170 (-3725 2000);
PAINT GREEN (-3725 2000);
DISPLAY INVISIBLE (-3725 2000);
FORCEPROP 2 LAST PATH I175
J 0
(-4125 2150);
DISPLAY 0.787234 (-4125 2150);
PAINT ORANGE (-4125 2150);
DISPLAY INVISIBLE (-4125 2150);
FORCEADD OFFPAGE..5
(-4225 2850);
FORCEPROP 2 LAST $XR0 43 
J 0
(-4449 2850);
DISPLAY 0.638298 (-4449 2850);
PAINT MONO (-4449 2850);
FORCEPROP 2 LAST $XR1 44 
J 0
(-4539 2850);
DISPLAY 0.638298 (-4539 2850);
PAINT MONO (-4539 2850);
FORCEPROP 2 LAST $XR2 45 
J 0
(-4629 2850);
DISPLAY 0.638298 (-4629 2850);
PAINT MONO (-4629 2850);
FORCEPROP 2 LAST $XR3 46 
J 0
(-4719 2850);
DISPLAY 0.638298 (-4719 2850);
PAINT MONO (-4719 2850);
FORCEPROP 2 LAST $XR4 47 
J 0
(-4809 2850);
DISPLAY 0.638298 (-4809 2850);
PAINT MONO (-4809 2850);
FORCEPROP 2 LAST $XR5 48 
J 0
(-4899 2850);
DISPLAY 0.638298 (-4899 2850);
PAINT MONO (-4899 2850);
FORCEPROP 2 LAST $XR6 50 
J 0
(-4989 2850);
DISPLAY 0.638298 (-4989 2850);
PAINT MONO (-4989 2850);
FORCEPROP 2 LAST $XR7 51 
J 0
(-5079 2850);
DISPLAY 0.638298 (-5079 2850);
PAINT MONO (-5079 2850);
FORCEPROP 2 LAST $XR8 52 
J 0
(-5169 2850);
DISPLAY 0.638298 (-5169 2850);
PAINT MONO (-5169 2850);
FORCEPROP 2 LAST $XR9 53 
J 0
(-5259 2850);
DISPLAY 0.638298 (-5259 2850);
PAINT MONO (-5259 2850);
FORCEPROP 2 LAST $XR10 54 
J 0
(-4449 2814);
DISPLAY 0.638298 (-4449 2814);
PAINT MONO (-4449 2814);
FORCEPROP 2 LAST $XR11 77 
J 0
(-4539 2814);
DISPLAY 0.638298 (-4539 2814);
PAINT MONO (-4539 2814);
FORCEPROP 2 LAST $XR12 78 
J 0
(-4629 2814);
DISPLAY 0.638298 (-4629 2814);
PAINT MONO (-4629 2814);
FORCEPROP 2 LAST $XR13 79 
J 0
(-4719 2814);
DISPLAY 0.638298 (-4719 2814);
PAINT MONO (-4719 2814);
FORCEPROP 2 LAST $XR14 80 
J 0
(-4809 2814);
DISPLAY 0.638298 (-4809 2814);
PAINT MONO (-4809 2814);
FORCEPROP 2 LAST $XR15 81 
J 0
(-4899 2814);
DISPLAY 0.638298 (-4899 2814);
PAINT MONO (-4899 2814);
FORCEPROP 2 LAST $XR16 82 
J 0
(-4989 2814);
DISPLAY 0.638298 (-4989 2814);
PAINT MONO (-4989 2814);
FORCEPROP 2 LAST $XR17 83 
J 0
(-5079 2814);
DISPLAY 0.638298 (-5079 2814);
PAINT MONO (-5079 2814);
FORCEPROP 2 LAST $XR18 84 
J 0
(-5169 2814);
DISPLAY 0.638298 (-5169 2814);
PAINT MONO (-5169 2814);
FORCEPROP 2 LAST $XR19 85 
J 0
(-5259 2814);
DISPLAY 0.638298 (-5259 2814);
PAINT MONO (-5259 2814);
FORCEPROP 2 LAST $XR20 86 
J 0
(-4449 2886);
DISPLAY 0.638298 (-4449 2886);
PAINT MONO (-4449 2886);
FORCEPROP 2 LAST $XR21 87 
J 0
(-4539 2886);
DISPLAY 0.638298 (-4539 2886);
PAINT MONO (-4539 2886);
FORCEPROP 2 LAST $XR22 88 
J 0
(-4629 2886);
DISPLAY 0.638298 (-4629 2886);
PAINT MONO (-4629 2886);
FORCEPROP 2 LAST $XR23 94 
J 0
(-4719 2886);
DISPLAY 0.638298 (-4719 2886);
PAINT MONO (-4719 2886);
FORCEPROP 2 LAST CDS_LIB mstr_standard
J 0
(-4225 2850);
DISPLAY 0.787234 (-4225 2850);
PAINT MONO (-4225 2850);
DISPLAY INVISIBLE (-4225 2850);
FORCEPROP 1 LAST OFFPAGE TRUE
J 0
(-3900 2725);
DISPLAY 1.404255 (-3900 2725);
PAINT GREEN (-3900 2725);
DISPLAY INVISIBLE (-3900 2725);
FORCEPROP 1 LAST COMMENT_BODY TRUE
J 0
(-4125 2775);
DISPLAY 1.404255 (-4125 2775);
PAINT GREEN (-4125 2775);
DISPLAY INVISIBLE (-4125 2775);
FORCEPROP 2 LAST PATH I176
J 0
(-4475 2900);
DISPLAY 0.787234 (-4475 2900);
PAINT ORANGE (-4475 2900);
DISPLAY INVISIBLE (-4475 2900);
FORCEADD GND..1
R 2
(-5100 2100);
FORCEPROP 3 LASTPIN (-5100 2150) SIG_NAME GND\g
J 0
(-5090 2160);
DISPLAY 0.659574 (-5090 2160);
PAINT MONO (-5090 2160);
DISPLAY INVISIBLE (-5090 2160);
FORCEPROP 1 LAST VOLTAGE 0
J 0
(-5100 2100);
PAINT SKYBLUE (-5100 2100);
DISPLAY INVISIBLE (-5100 2100);
FORCEPROP 2 LAST CDS_LIB mstr_symbols
J 0
(-5100 2100);
DISPLAY 0.787234 (-5100 2100);
PAINT MONO (-5100 2100);
DISPLAY INVISIBLE (-5100 2100);
FORCEPROP 1 LAST SIZE 1B
J 2
(-5175 2050);
DISPLAY 1.170213 (-5175 2050);
PAINT GREEN (-5175 2050);
DISPLAY INVISIBLE (-5175 2050);
FORCEPROP 2 LAST BOM_COST MEM
J 0
(-5100 2105);
PAINT ORANGE (-5100 2105);
DISPLAY INVISIBLE (-5100 2105);
FORCEPROP 1 LAST BODY_TYPE PLUMBING
J 2
(-5055 2057);
DISPLAY 0.340426 (-5055 2057);
PAINT GREEN (-5055 2057);
DISPLAY INVISIBLE (-5055 2057);
FORCEPROP 1 LAST PATH I178
J 2
(-5175 2100);
DISPLAY 1.404255 (-5175 2100);
PAINT GREEN (-5175 2100);
DISPLAY INVISIBLE (-5175 2100);
FORCEPROP 2 LAST ROOM DDR4_CH_B
J 0
(-5100 2105);
PAINT ORANGE (-5100 2105);
DISPLAY INVISIBLE (-5100 2105);
FORCEPROP 1 LAST HDL_POWER GND
J 2
(-5100 2250);
DISPLAY 0.553191 (-5100 2250);
PAINT GREEN (-5100 2250);
DISPLAY INVISIBLE (-5100 2250);
FORCEADD CAP_A..1
R 2
(-4650 1800);
FORCEPROP 1 LAST LOCATION C4B12
J 2
(-4700 1900);
DISPLAY 0.617021 (-4700 1900);
PAINT AQUA (-4700 1900);
FORCEPROP 1 LAST PART_NUMBER A36096-045
J 2
(-4700 1650);
DISPLAY 0.617021 (-4700 1650);
PAINT BLUE (-4700 1650);
FORCEPROP 1 LAST VALUE 0.01UF
J 2
(-4700 1850);
DISPLAY 0.617021 (-4700 1850);
PAINT SKYBLUE (-4700 1850);
FORCEPROP 1 LAST TOLERANCE 10%
J 2
(-4700 1750);
DISPLAY 0.617021 (-4700 1750);
PAINT SKYBLUE (-4700 1750);
FORCEPROP 1 LAST PACK_TYPE 0402V
J 2
(-4700 1600);
DISPLAY 0.617021 (-4700 1600);
PAINT SKYBLUE (-4700 1600);
FORCEPROP 1 LAST VOLTAGE 25V
J 2
(-4700 1800);
DISPLAY 0.617021 (-4700 1800);
PAINT SKYBLUE (-4700 1800);
FORCEPROP 1 LAST MATERIAL X7R
J 2
(-4700 1700);
DISPLAY 0.617021 (-4700 1700);
PAINT SKYBLUE (-4700 1700);
FORCEPROP 2 LAST CDS_LOCATION C4B12
J 2
(-4700 1900);
DISPLAY 0.617021 (-4700 1900);
PAINT AQUA (-4700 1900);
DISPLAY INVISIBLE (-4700 1900);
FORCEPROP 2 LAST BOM_COST MEM
J 0
(-4650 1800);
PAINT ORANGE (-4650 1800);
DISPLAY INVISIBLE (-4650 1800);
FORCEPROP 2 LAST CDS_LIB dev_discrete
J 0
(-4650 1800);
PAINT ORANGE (-4650 1800);
DISPLAY INVISIBLE (-4650 1800);
FORCEPROP 2 LAST CDS_SEC 1
J 2
(-4700 2000);
PAINT MONO (-4700 2000);
DISPLAY INVISIBLE (-4700 2000);
FORCEPROP 2 LAST $SEC 1
J 0
(-4700 2000);
PAINT MONO (-4700 2000);
DISPLAY INVISIBLE (-4700 2000);
FORCEPROP 1 LAST PATH I179
J 2
(-4700 1950);
DISPLAY 0.978723 (-4700 1950);
PAINT WHITE (-4700 1950);
DISPLAY INVISIBLE (-4700 1950);
FORCEPROP 2 LAST ROOM DDR4_CH_B
J 0
(-4650 1800);
PAINT ORANGE (-4650 1800);
DISPLAY INVISIBLE (-4650 1800);
FORCEPROP 1 LASTPIN (-4650 1900) $PN 1
J 2
(-4660 1880);
DISPLAY 0.787234 (-4660 1880);
PAINT ORANGE (-4660 1880);
DISPLAY INVISIBLE (-4660 1880);
FORCEPROP 1 LASTPIN (-4650 1700) $PN 2
J 2
(-4660 1680);
DISPLAY 0.787234 (-4660 1680);
PAINT ORANGE (-4660 1680);
DISPLAY INVISIBLE (-4660 1680);
FORCEADD GND..1
(-4650 1550);
FORCEPROP 3 LASTPIN (-4650 1600) SIG_NAME GND\g
J 0
(-4640 1610);
DISPLAY 0.659574 (-4640 1610);
PAINT MONO (-4640 1610);
DISPLAY INVISIBLE (-4640 1610);
FORCEPROP 1 LAST VOLTAGE 0
J 0
(-4650 1550);
PAINT SKYBLUE (-4650 1550);
DISPLAY INVISIBLE (-4650 1550);
FORCEPROP 1 LAST SIZE 1B
J 0
(-4575 1500);
DISPLAY 1.787234 (-4575 1500);
PAINT GREEN (-4575 1500);
DISPLAY INVISIBLE (-4575 1500);
FORCEPROP 2 LAST CDS_LIB mstr_symbols
J 0
(-4650 1550);
PAINT ORANGE (-4650 1550);
DISPLAY INVISIBLE (-4650 1550);
FORCEPROP 2 LAST BOM_COST MEM
J 0
(-4650 1555);
PAINT ORANGE (-4650 1555);
DISPLAY INVISIBLE (-4650 1555);
FORCEPROP 1 LAST BODY_TYPE PLUMBING
J 0
(-4695 1507);
DISPLAY 0.340426 (-4695 1507);
PAINT GREEN (-4695 1507);
DISPLAY INVISIBLE (-4695 1507);
FORCEPROP 1 LAST PATH I180
J 0
(-4575 1550);
DISPLAY 1.404255 (-4575 1550);
PAINT GREEN (-4575 1550);
DISPLAY INVISIBLE (-4575 1550);
FORCEPROP 2 LAST ROOM DDR4_CH_B
J 0
(-4650 1555);
PAINT ORANGE (-4650 1555);
DISPLAY INVISIBLE (-4650 1555);
FORCEPROP 1 LAST HDL_POWER GND
J 0
(-4650 1700);
DISPLAY 1.404255 (-4650 1700);
PAINT GREEN (-4650 1700);
DISPLAY INVISIBLE (-4650 1700);
FORCEADD PVPP_DEF..1
(-750 2950);
FORCEPROP 3 LASTPIN (-750 2900) SIG_NAME PVPP_DEF\g
J 0
(-740 2910);
DISPLAY 0.659574 (-740 2910);
PAINT MONO (-740 2910);
DISPLAY INVISIBLE (-740 2910);
FORCEPROP 1 LAST VOLTAGE 2.5V
J 0
(-795 2907);
DISPLAY 0.340426 (-795 2907);
PAINT SKYBLUE (-795 2907);
DISPLAY INVISIBLE (-795 2907);
FORCEPROP 0 LAST BOM_COST MEM
J 0
(-750 3050);
PAINT ORANGE (-750 3050);
DISPLAY INVISIBLE (-750 3050);
FORCEPROP 2 LAST CDS_LIB mstr_symbols
J 0
(-750 2950);
PAINT ORANGE (-750 2950);
DISPLAY INVISIBLE (-750 2950);
FORCEPROP 1 LAST BODY_TYPE PLUMBING
J 0
(-795 2907);
DISPLAY 0.340426 (-795 2907);
PAINT GREEN (-795 2907);
DISPLAY INVISIBLE (-795 2907);
FORCEPROP 1 LAST PATH I181
J 0
(-700 2975);
DISPLAY 0.872340 (-700 2975);
PAINT AQUA (-700 2975);
DISPLAY INVISIBLE (-700 2975);
FORCEPROP 2 LAST ROOM DDR4_CH_B
J 0
(-750 3050);
PAINT ORANGE (-750 3050);
DISPLAY INVISIBLE (-750 3050);
FORCEPROP 1 LAST HDL_POWER PVPP_DEF
J 1
(-750 3000);
DISPLAY 0.872340 (-750 3000);
PAINT GREEN (-750 3000);
DISPLAY INVISIBLE (-750 3000);
FORCEADD PVPP_DEF..1
(-5100 2500);
FORCEPROP 3 LASTPIN (-5100 2450) SIG_NAME PVPP_DEF\g
J 0
(-5090 2460);
DISPLAY 0.659574 (-5090 2460);
PAINT MONO (-5090 2460);
DISPLAY INVISIBLE (-5090 2460);
FORCEPROP 1 LAST VOLTAGE 2.5V
J 0
(-5145 2457);
DISPLAY 0.340426 (-5145 2457);
PAINT SKYBLUE (-5145 2457);
DISPLAY INVISIBLE (-5145 2457);
FORCEPROP 0 LAST BOM_COST MEM
J 0
(-5100 2600);
PAINT ORANGE (-5100 2600);
DISPLAY INVISIBLE (-5100 2600);
FORCEPROP 2 LAST CDS_LIB mstr_symbols
J 0
(-5100 2500);
PAINT ORANGE (-5100 2500);
DISPLAY INVISIBLE (-5100 2500);
FORCEPROP 1 LAST BODY_TYPE PLUMBING
J 0
(-5145 2457);
DISPLAY 0.340426 (-5145 2457);
PAINT GREEN (-5145 2457);
DISPLAY INVISIBLE (-5145 2457);
FORCEPROP 1 LAST PATH I182
J 0
(-5050 2525);
DISPLAY 0.872340 (-5050 2525);
PAINT AQUA (-5050 2525);
DISPLAY INVISIBLE (-5050 2525);
FORCEPROP 2 LAST ROOM DDR4_CH_B
J 0
(-5100 2600);
PAINT ORANGE (-5100 2600);
DISPLAY INVISIBLE (-5100 2600);
FORCEPROP 1 LAST HDL_POWER PVPP_DEF
J 1
(-5100 2550);
DISPLAY 0.872340 (-5100 2550);
PAINT GREEN (-5100 2550);
DISPLAY INVISIBLE (-5100 2550);
FORCEADD OFFPAGE..1
(-3900 1700);
FORCEPROP 2 LAST $XR0 89 
J 0
(-4121 1700);
DISPLAY 0.638298 (-4121 1700);
PAINT MONO (-4121 1700);
FORCEPROP 2 LAST $XR1 50 
J 0
(-4211 1700);
DISPLAY 0.638298 (-4211 1700);
PAINT MONO (-4211 1700);
FORCEPROP 2 LAST $XR2 51 
J 0
(-4301 1700);
DISPLAY 0.638298 (-4301 1700);
PAINT MONO (-4301 1700);
FORCEPROP 2 LAST $XR3 52 
J 0
(-4391 1700);
DISPLAY 0.638298 (-4391 1700);
PAINT MONO (-4391 1700);
FORCEPROP 2 LAST $XR4 53 
J 0
(-4481 1700);
DISPLAY 0.638298 (-4481 1700);
PAINT MONO (-4481 1700);
FORCEPROP 2 LAST $XR5 54 
J 0
(-4571 1700);
DISPLAY 0.638298 (-4571 1700);
PAINT MONO (-4571 1700);
FORCEPROP 2 LAST CDS_LIB mstr_standard
J 0
(-3900 1700);
PAINT ORANGE (-3900 1700);
DISPLAY INVISIBLE (-3900 1700);
FORCEPROP 1 LAST OFFPAGE TRUE
J 0
(-3575 1575);
DISPLAY 0.936170 (-3575 1575);
PAINT GREEN (-3575 1575);
DISPLAY INVISIBLE (-3575 1575);
FORCEPROP 1 LAST COMMENT_BODY TRUE
J 0
(-3775 1600);
DISPLAY 0.936170 (-3775 1600);
PAINT GREEN (-3775 1600);
DISPLAY INVISIBLE (-3775 1600);
FORCEPROP 2 LAST PATH I183
J 0
(-3850 1775);
PAINT ORANGE (-3850 1775);
DISPLAY INVISIBLE (-3850 1775);
FORCEADD P12V_NVDIMM_DEF..1
(650 3025);
FORCEPROP 3 LASTPIN (650 2975) SIG_NAME P12V_NVDIMM_DEF\g
J 0
(660 2985);
DISPLAY 0.659574 (660 2985);
PAINT MONO (660 2985);
DISPLAY INVISIBLE (660 2985);
FORCEPROP 1 LAST VOLTAGE 12.0
J 0
(605 2982);
DISPLAY 0.340426 (605 2982);
PAINT SKYBLUE (605 2982);
DISPLAY INVISIBLE (605 2982);
FORCEPROP 2 LAST CDS_LIB mstr_symbols
J 0
(650 3025);
PAINT ORANGE (650 3025);
DISPLAY INVISIBLE (650 3025);
FORCEPROP 1 LAST BODY_TYPE PLUMBING
J 0
(605 2982);
DISPLAY 0.340426 (605 2982);
PAINT GREEN (605 2982);
DISPLAY INVISIBLE (605 2982);
FORCEPROP 1 LAST PATH I184
J 0
(700 3050);
DISPLAY 0.872340 (700 3050);
PAINT AQUA (700 3050);
DISPLAY INVISIBLE (700 3050);
FORCEPROP 1 LAST HDL_POWER P12V_NVDIMM_DEF
J 1
(650 3075);
DISPLAY 0.872340 (650 3075);
PAINT GREEN (650 3075);
DISPLAY INVISIBLE (650 3075);
FORCEADD TAP..6
R 2
(900 4550);
FORCEPROP 3 LASTPIN (850 4550) SIG_NAME M_D_DQS_DN<11>
J 0
(860 4560);
DISPLAY 0.659574 (860 4560);
PAINT MONO (860 4560);
DISPLAY INVISIBLE (860 4560);
FORCEPROP 1 LASTPIN (850 4550) BN 11
J 2
(900 4560);
DISPLAY 0.617021 (900 4560);
PAINT PINK (900 4560);
FORCEPROP 2 LAST CDS_LIB mstr_standard
J 0
(900 4550);
DISPLAY 0.787234 (900 4550);
PAINT MONO (900 4550);
DISPLAY INVISIBLE (900 4550);
FORCEPROP 1 LAST BODY_TYPE PLUMBING
J 2
(900 4500);
DISPLAY 1.234043 (900 4500);
PAINT GREEN (900 4500);
DISPLAY INVISIBLE (900 4500);
FORCEPROP 1 LAST HDL_TAP TRUE
J 2
(575 4425);
DISPLAY 1.234043 (575 4425);
PAINT GREEN (575 4425);
DISPLAY INVISIBLE (575 4425);
FORCEPROP 1 LAST PATH I19
J 2
(900 4550);
DISPLAY 0.936170 (900 4550);
PAINT GREEN (900 4550);
DISPLAY INVISIBLE (900 4550);
FORCEADD OFFPAGE..3
(1650 5200);
FORCEPROP 2 LAST $XR0 26 
J 0
(1864 5200);
DISPLAY 0.638298 (1864 5200);
PAINT MONO (1864 5200);
FORCEPROP 2 LAST $XR1 50 
J 0
(1954 5200);
DISPLAY 0.638298 (1954 5200);
PAINT MONO (1954 5200);
FORCEPROP 2 LAST CDS_LIB mstr_standard
J 0
(1650 5200);
DISPLAY 0.787234 (1650 5200);
PAINT MONO (1650 5200);
DISPLAY INVISIBLE (1650 5200);
FORCEPROP 1 LAST OFFPAGE TRUE
J 0
(1975 5075);
DISPLAY 0.936170 (1975 5075);
PAINT GREEN (1975 5075);
DISPLAY INVISIBLE (1975 5075);
FORCEPROP 1 LAST COMMENT_BODY TRUE
J 0
(1600 5100);
DISPLAY 0.936170 (1600 5100);
PAINT GREEN (1600 5100);
DISPLAY INVISIBLE (1600 5100);
FORCEPROP 2 LAST PATH I2
J 0
(1850 5275);
DISPLAY 0.787234 (1850 5275);
PAINT MONO (1850 5275);
DISPLAY INVISIBLE (1850 5275);
FORCEADD TAP..6
R 2
(900 4450);
FORCEPROP 3 LASTPIN (850 4450) SIG_NAME M_D_DQS_DN<10>
J 0
(860 4460);
DISPLAY 0.659574 (860 4460);
PAINT MONO (860 4460);
DISPLAY INVISIBLE (860 4460);
FORCEPROP 1 LASTPIN (850 4450) BN 10
J 2
(900 4460);
DISPLAY 0.617021 (900 4460);
PAINT PINK (900 4460);
FORCEPROP 2 LAST CDS_LIB mstr_standard
J 0
(900 4450);
DISPLAY 0.787234 (900 4450);
PAINT MONO (900 4450);
DISPLAY INVISIBLE (900 4450);
FORCEPROP 1 LAST BODY_TYPE PLUMBING
J 2
(900 4400);
DISPLAY 1.234043 (900 4400);
PAINT GREEN (900 4400);
DISPLAY INVISIBLE (900 4400);
FORCEPROP 1 LAST HDL_TAP TRUE
J 2
(575 4325);
DISPLAY 1.234043 (575 4325);
PAINT GREEN (575 4325);
DISPLAY INVISIBLE (575 4325);
FORCEPROP 1 LAST PATH I20
J 2
(900 4450);
DISPLAY 0.936170 (900 4450);
PAINT GREEN (900 4450);
DISPLAY INVISIBLE (900 4450);
FORCEADD TAP..6
R 2
(900 4350);
FORCEPROP 3 LASTPIN (850 4350) SIG_NAME M_D_DQS_DN<9>
J 0
(860 4360);
DISPLAY 0.659574 (860 4360);
PAINT MONO (860 4360);
DISPLAY INVISIBLE (860 4360);
FORCEPROP 1 LASTPIN (850 4350) BN 9
J 2
(900 4360);
DISPLAY 0.617021 (900 4360);
PAINT PINK (900 4360);
FORCEPROP 2 LAST CDS_LIB mstr_standard
J 0
(900 4350);
DISPLAY 0.787234 (900 4350);
PAINT MONO (900 4350);
DISPLAY INVISIBLE (900 4350);
FORCEPROP 1 LAST BODY_TYPE PLUMBING
J 2
(900 4300);
DISPLAY 1.234043 (900 4300);
PAINT GREEN (900 4300);
DISPLAY INVISIBLE (900 4300);
FORCEPROP 1 LAST HDL_TAP TRUE
J 2
(575 4225);
DISPLAY 1.234043 (575 4225);
PAINT GREEN (575 4225);
DISPLAY INVISIBLE (575 4225);
FORCEPROP 1 LAST PATH I21
J 2
(900 4350);
DISPLAY 0.936170 (900 4350);
PAINT GREEN (900 4350);
DISPLAY INVISIBLE (900 4350);
FORCEADD TAP..6
R 2
(900 4250);
FORCEPROP 3 LASTPIN (850 4250) SIG_NAME M_D_DQS_DN<8>
J 0
(860 4260);
DISPLAY 0.659574 (860 4260);
PAINT MONO (860 4260);
DISPLAY INVISIBLE (860 4260);
FORCEPROP 1 LASTPIN (850 4250) BN 8
J 2
(900 4260);
DISPLAY 0.617021 (900 4260);
PAINT PINK (900 4260);
FORCEPROP 2 LAST CDS_LIB mstr_standard
J 0
(900 4250);
DISPLAY 0.787234 (900 4250);
PAINT MONO (900 4250);
DISPLAY INVISIBLE (900 4250);
FORCEPROP 1 LAST BODY_TYPE PLUMBING
J 2
(900 4200);
DISPLAY 1.234043 (900 4200);
PAINT GREEN (900 4200);
DISPLAY INVISIBLE (900 4200);
FORCEPROP 1 LAST HDL_TAP TRUE
J 2
(575 4125);
DISPLAY 1.234043 (575 4125);
PAINT GREEN (575 4125);
DISPLAY INVISIBLE (575 4125);
FORCEPROP 1 LAST PATH I22
J 2
(900 4250);
DISPLAY 0.936170 (900 4250);
PAINT GREEN (900 4250);
DISPLAY INVISIBLE (900 4250);
FORCEADD TAP..6
R 2
(900 4150);
FORCEPROP 3 LASTPIN (850 4150) SIG_NAME M_D_DQS_DN<7>
J 0
(860 4160);
DISPLAY 0.659574 (860 4160);
PAINT MONO (860 4160);
DISPLAY INVISIBLE (860 4160);
FORCEPROP 1 LASTPIN (850 4150) BN 7
J 2
(900 4160);
DISPLAY 0.617021 (900 4160);
PAINT PINK (900 4160);
FORCEPROP 2 LAST CDS_LIB mstr_standard
J 0
(900 4150);
DISPLAY 0.787234 (900 4150);
PAINT MONO (900 4150);
DISPLAY INVISIBLE (900 4150);
FORCEPROP 1 LAST BODY_TYPE PLUMBING
J 2
(900 4100);
DISPLAY 1.234043 (900 4100);
PAINT GREEN (900 4100);
DISPLAY INVISIBLE (900 4100);
FORCEPROP 1 LAST HDL_TAP TRUE
J 2
(575 4025);
DISPLAY 1.234043 (575 4025);
PAINT GREEN (575 4025);
DISPLAY INVISIBLE (575 4025);
FORCEPROP 1 LAST PATH I23
J 2
(900 4150);
DISPLAY 0.936170 (900 4150);
PAINT GREEN (900 4150);
DISPLAY INVISIBLE (900 4150);
FORCEADD TAP..6
R 2
(650 4400);
FORCEPROP 3 LASTPIN (600 4400) SIG_NAME M_D_DQS_DP<9>
J 0
(610 4410);
DISPLAY 0.659574 (610 4410);
PAINT MONO (610 4410);
DISPLAY INVISIBLE (610 4410);
FORCEPROP 1 LASTPIN (600 4400) BN 9
J 2
(650 4410);
DISPLAY 0.617021 (650 4410);
PAINT PINK (650 4410);
FORCEPROP 2 LAST CDS_LIB mstr_standard
J 0
(650 4400);
DISPLAY 0.787234 (650 4400);
PAINT MONO (650 4400);
DISPLAY INVISIBLE (650 4400);
FORCEPROP 1 LAST BODY_TYPE PLUMBING
J 2
(650 4350);
DISPLAY 1.234043 (650 4350);
PAINT GREEN (650 4350);
DISPLAY INVISIBLE (650 4350);
FORCEPROP 1 LAST HDL_TAP TRUE
J 2
(325 4275);
DISPLAY 1.234043 (325 4275);
PAINT GREEN (325 4275);
DISPLAY INVISIBLE (325 4275);
FORCEPROP 1 LAST PATH I24
J 2
(650 4400);
DISPLAY 0.936170 (650 4400);
PAINT GREEN (650 4400);
DISPLAY INVISIBLE (650 4400);
FORCEADD TAP..6
R 2
(650 4500);
FORCEPROP 3 LASTPIN (600 4500) SIG_NAME M_D_DQS_DP<10>
J 0
(610 4510);
DISPLAY 0.659574 (610 4510);
PAINT MONO (610 4510);
DISPLAY INVISIBLE (610 4510);
FORCEPROP 1 LASTPIN (600 4500) BN 10
J 2
(650 4510);
DISPLAY 0.617021 (650 4510);
PAINT PINK (650 4510);
FORCEPROP 2 LAST CDS_LIB mstr_standard
J 0
(650 4500);
DISPLAY 0.787234 (650 4500);
PAINT MONO (650 4500);
DISPLAY INVISIBLE (650 4500);
FORCEPROP 1 LAST BODY_TYPE PLUMBING
J 2
(650 4450);
DISPLAY 1.234043 (650 4450);
PAINT GREEN (650 4450);
DISPLAY INVISIBLE (650 4450);
FORCEPROP 1 LAST HDL_TAP TRUE
J 2
(325 4375);
DISPLAY 1.234043 (325 4375);
PAINT GREEN (325 4375);
DISPLAY INVISIBLE (325 4375);
FORCEPROP 1 LAST PATH I25
J 2
(650 4500);
DISPLAY 0.936170 (650 4500);
PAINT GREEN (650 4500);
DISPLAY INVISIBLE (650 4500);
FORCEADD TAP..6
R 2
(650 4300);
FORCEPROP 3 LASTPIN (600 4300) SIG_NAME M_D_DQS_DP<8>
J 0
(610 4310);
DISPLAY 0.659574 (610 4310);
PAINT MONO (610 4310);
DISPLAY INVISIBLE (610 4310);
FORCEPROP 1 LASTPIN (600 4300) BN 8
J 2
(650 4310);
DISPLAY 0.617021 (650 4310);
PAINT PINK (650 4310);
FORCEPROP 2 LAST CDS_LIB mstr_standard
J 0
(650 4300);
DISPLAY 0.787234 (650 4300);
PAINT MONO (650 4300);
DISPLAY INVISIBLE (650 4300);
FORCEPROP 1 LAST BODY_TYPE PLUMBING
J 2
(650 4250);
DISPLAY 1.234043 (650 4250);
PAINT GREEN (650 4250);
DISPLAY INVISIBLE (650 4250);
FORCEPROP 1 LAST HDL_TAP TRUE
J 2
(325 4175);
DISPLAY 1.234043 (325 4175);
PAINT GREEN (325 4175);
DISPLAY INVISIBLE (325 4175);
FORCEPROP 1 LAST PATH I26
J 2
(650 4300);
DISPLAY 0.936170 (650 4300);
PAINT GREEN (650 4300);
DISPLAY INVISIBLE (650 4300);
FORCEADD TAP..6
R 2
(650 4100);
FORCEPROP 3 LASTPIN (600 4100) SIG_NAME M_D_DQS_DP<6>
J 0
(610 4110);
DISPLAY 0.659574 (610 4110);
PAINT MONO (610 4110);
DISPLAY INVISIBLE (610 4110);
FORCEPROP 1 LASTPIN (600 4100) BN 6
J 2
(650 4110);
DISPLAY 0.617021 (650 4110);
PAINT PINK (650 4110);
FORCEPROP 2 LAST CDS_LIB mstr_standard
J 0
(650 4100);
DISPLAY 0.787234 (650 4100);
PAINT MONO (650 4100);
DISPLAY INVISIBLE (650 4100);
FORCEPROP 1 LAST BODY_TYPE PLUMBING
J 2
(650 4050);
DISPLAY 1.234043 (650 4050);
PAINT GREEN (650 4050);
DISPLAY INVISIBLE (650 4050);
FORCEPROP 1 LAST HDL_TAP TRUE
J 2
(325 3975);
DISPLAY 1.234043 (325 3975);
PAINT GREEN (325 3975);
DISPLAY INVISIBLE (325 3975);
FORCEPROP 1 LAST PATH I27
J 2
(650 4100);
DISPLAY 0.936170 (650 4100);
PAINT GREEN (650 4100);
DISPLAY INVISIBLE (650 4100);
FORCEADD TAP..6
R 2
(650 4200);
FORCEPROP 3 LASTPIN (600 4200) SIG_NAME M_D_DQS_DP<7>
J 0
(610 4210);
DISPLAY 0.659574 (610 4210);
PAINT MONO (610 4210);
DISPLAY INVISIBLE (610 4210);
FORCEPROP 1 LASTPIN (600 4200) BN 7
J 2
(650 4210);
DISPLAY 0.617021 (650 4210);
PAINT PINK (650 4210);
FORCEPROP 2 LAST CDS_LIB mstr_standard
J 0
(650 4200);
DISPLAY 0.787234 (650 4200);
PAINT MONO (650 4200);
DISPLAY INVISIBLE (650 4200);
FORCEPROP 1 LAST BODY_TYPE PLUMBING
J 2
(650 4150);
DISPLAY 1.234043 (650 4150);
PAINT GREEN (650 4150);
DISPLAY INVISIBLE (650 4150);
FORCEPROP 1 LAST HDL_TAP TRUE
J 2
(325 4075);
DISPLAY 1.234043 (325 4075);
PAINT GREEN (325 4075);
DISPLAY INVISIBLE (325 4075);
FORCEPROP 1 LAST PATH I28
J 2
(650 4200);
DISPLAY 0.936170 (650 4200);
PAINT GREEN (650 4200);
DISPLAY INVISIBLE (650 4200);
FORCEADD TAP..6
R 2
(900 4050);
FORCEPROP 3 LASTPIN (850 4050) SIG_NAME M_D_DQS_DN<6>
J 0
(860 4060);
DISPLAY 0.659574 (860 4060);
PAINT MONO (860 4060);
DISPLAY INVISIBLE (860 4060);
FORCEPROP 1 LASTPIN (850 4050) BN 6
J 2
(900 4060);
DISPLAY 0.617021 (900 4060);
PAINT PINK (900 4060);
FORCEPROP 2 LAST CDS_LIB mstr_standard
J 0
(900 4050);
DISPLAY 0.787234 (900 4050);
PAINT MONO (900 4050);
DISPLAY INVISIBLE (900 4050);
FORCEPROP 1 LAST BODY_TYPE PLUMBING
J 2
(900 4000);
DISPLAY 1.234043 (900 4000);
PAINT GREEN (900 4000);
DISPLAY INVISIBLE (900 4000);
FORCEPROP 1 LAST HDL_TAP TRUE
J 2
(575 3925);
DISPLAY 1.234043 (575 3925);
PAINT GREEN (575 3925);
DISPLAY INVISIBLE (575 3925);
FORCEPROP 1 LAST PATH I29
J 2
(900 4050);
DISPLAY 0.936170 (900 4050);
PAINT GREEN (900 4050);
DISPLAY INVISIBLE (900 4050);
FORCEADD TAP..6
R 2
(900 5150);
FORCEPROP 3 LASTPIN (850 5150) SIG_NAME M_D_DQS_DN<17>
J 0
(860 5160);
DISPLAY 0.659574 (860 5160);
PAINT MONO (860 5160);
DISPLAY INVISIBLE (860 5160);
FORCEPROP 1 LASTPIN (850 5150) BN 17
J 2
(900 5160);
DISPLAY 0.617021 (900 5160);
PAINT PINK (900 5160);
FORCEPROP 2 LAST CDS_LIB mstr_standard
J 2
(900 5150);
DISPLAY 0.787234 (900 5150);
PAINT MONO (900 5150);
DISPLAY INVISIBLE (900 5150);
FORCEPROP 1 LAST BODY_TYPE PLUMBING
J 2
(900 5100);
DISPLAY 1.234043 (900 5100);
PAINT GREEN (900 5100);
DISPLAY INVISIBLE (900 5100);
FORCEPROP 1 LAST HDL_TAP TRUE
J 2
(575 5025);
DISPLAY 1.234043 (575 5025);
PAINT GREEN (575 5025);
DISPLAY INVISIBLE (575 5025);
FORCEPROP 1 LAST PATH I3
J 2
(900 5150);
DISPLAY 0.936170 (900 5150);
PAINT GREEN (900 5150);
DISPLAY INVISIBLE (900 5150);
FORCEADD TAP..6
R 2
(900 3950);
FORCEPROP 3 LASTPIN (850 3950) SIG_NAME M_D_DQS_DN<5>
J 0
(860 3960);
DISPLAY 0.659574 (860 3960);
PAINT MONO (860 3960);
DISPLAY INVISIBLE (860 3960);
FORCEPROP 1 LASTPIN (850 3950) BN 5
J 2
(900 3960);
DISPLAY 0.617021 (900 3960);
PAINT PINK (900 3960);
FORCEPROP 2 LAST CDS_LIB mstr_standard
J 0
(900 3950);
DISPLAY 0.787234 (900 3950);
PAINT MONO (900 3950);
DISPLAY INVISIBLE (900 3950);
FORCEPROP 1 LAST BODY_TYPE PLUMBING
J 2
(900 3900);
DISPLAY 1.234043 (900 3900);
PAINT GREEN (900 3900);
DISPLAY INVISIBLE (900 3900);
FORCEPROP 1 LAST HDL_TAP TRUE
J 2
(575 3825);
DISPLAY 1.234043 (575 3825);
PAINT GREEN (575 3825);
DISPLAY INVISIBLE (575 3825);
FORCEPROP 1 LAST PATH I30
J 2
(900 3950);
DISPLAY 0.936170 (900 3950);
PAINT GREEN (900 3950);
DISPLAY INVISIBLE (900 3950);
FORCEADD TAP..6
R 2
(900 3850);
FORCEPROP 3 LASTPIN (850 3850) SIG_NAME M_D_DQS_DN<4>
J 0
(860 3860);
DISPLAY 0.659574 (860 3860);
PAINT MONO (860 3860);
DISPLAY INVISIBLE (860 3860);
FORCEPROP 1 LASTPIN (850 3850) BN 4
J 2
(900 3860);
DISPLAY 0.617021 (900 3860);
PAINT PINK (900 3860);
FORCEPROP 2 LAST CDS_LIB mstr_standard
J 0
(900 3850);
DISPLAY 0.787234 (900 3850);
PAINT MONO (900 3850);
DISPLAY INVISIBLE (900 3850);
FORCEPROP 1 LAST BODY_TYPE PLUMBING
J 2
(900 3800);
DISPLAY 1.234043 (900 3800);
PAINT GREEN (900 3800);
DISPLAY INVISIBLE (900 3800);
FORCEPROP 1 LAST HDL_TAP TRUE
J 2
(575 3725);
DISPLAY 1.234043 (575 3725);
PAINT GREEN (575 3725);
DISPLAY INVISIBLE (575 3725);
FORCEPROP 1 LAST PATH I31
J 2
(900 3850);
DISPLAY 0.936170 (900 3850);
PAINT GREEN (900 3850);
DISPLAY INVISIBLE (900 3850);
FORCEADD TAP..6
R 2
(900 3750);
FORCEPROP 3 LASTPIN (850 3750) SIG_NAME M_D_DQS_DN<3>
J 0
(860 3760);
DISPLAY 0.659574 (860 3760);
PAINT MONO (860 3760);
DISPLAY INVISIBLE (860 3760);
FORCEPROP 1 LASTPIN (850 3750) BN 3
J 2
(900 3760);
DISPLAY 0.617021 (900 3760);
PAINT PINK (900 3760);
FORCEPROP 2 LAST CDS_LIB mstr_standard
J 0
(900 3750);
DISPLAY 0.787234 (900 3750);
PAINT MONO (900 3750);
DISPLAY INVISIBLE (900 3750);
FORCEPROP 1 LAST BODY_TYPE PLUMBING
J 2
(900 3700);
DISPLAY 1.234043 (900 3700);
PAINT GREEN (900 3700);
DISPLAY INVISIBLE (900 3700);
FORCEPROP 1 LAST HDL_TAP TRUE
J 2
(575 3625);
DISPLAY 1.234043 (575 3625);
PAINT GREEN (575 3625);
DISPLAY INVISIBLE (575 3625);
FORCEPROP 1 LAST PATH I32
J 2
(900 3750);
DISPLAY 0.936170 (900 3750);
PAINT GREEN (900 3750);
DISPLAY INVISIBLE (900 3750);
FORCEADD TAP..6
R 2
(900 3650);
FORCEPROP 3 LASTPIN (850 3650) SIG_NAME M_D_DQS_DN<2>
J 0
(860 3660);
DISPLAY 0.659574 (860 3660);
PAINT MONO (860 3660);
DISPLAY INVISIBLE (860 3660);
FORCEPROP 1 LASTPIN (850 3650) BN 2
J 2
(900 3660);
DISPLAY 0.617021 (900 3660);
PAINT PINK (900 3660);
FORCEPROP 2 LAST CDS_LIB mstr_standard
J 0
(900 3650);
DISPLAY 0.787234 (900 3650);
PAINT MONO (900 3650);
DISPLAY INVISIBLE (900 3650);
FORCEPROP 1 LAST BODY_TYPE PLUMBING
J 2
(900 3600);
DISPLAY 1.234043 (900 3600);
PAINT GREEN (900 3600);
DISPLAY INVISIBLE (900 3600);
FORCEPROP 1 LAST HDL_TAP TRUE
J 2
(575 3525);
DISPLAY 1.234043 (575 3525);
PAINT GREEN (575 3525);
DISPLAY INVISIBLE (575 3525);
FORCEPROP 1 LAST PATH I33
J 2
(900 3650);
DISPLAY 0.936170 (900 3650);
PAINT GREEN (900 3650);
DISPLAY INVISIBLE (900 3650);
FORCEADD TAP..6
R 2
(650 3900);
FORCEPROP 3 LASTPIN (600 3900) SIG_NAME M_D_DQS_DP<4>
J 0
(610 3910);
DISPLAY 0.659574 (610 3910);
PAINT MONO (610 3910);
DISPLAY INVISIBLE (610 3910);
FORCEPROP 1 LASTPIN (600 3900) BN 4
J 2
(650 3910);
DISPLAY 0.617021 (650 3910);
PAINT PINK (650 3910);
FORCEPROP 2 LAST CDS_LIB mstr_standard
J 0
(650 3900);
DISPLAY 0.787234 (650 3900);
PAINT MONO (650 3900);
DISPLAY INVISIBLE (650 3900);
FORCEPROP 1 LAST BODY_TYPE PLUMBING
J 2
(650 3850);
DISPLAY 1.234043 (650 3850);
PAINT GREEN (650 3850);
DISPLAY INVISIBLE (650 3850);
FORCEPROP 1 LAST HDL_TAP TRUE
J 2
(325 3775);
DISPLAY 1.234043 (325 3775);
PAINT GREEN (325 3775);
DISPLAY INVISIBLE (325 3775);
FORCEPROP 1 LAST PATH I34
J 2
(650 3900);
DISPLAY 0.936170 (650 3900);
PAINT GREEN (650 3900);
DISPLAY INVISIBLE (650 3900);
FORCEADD TAP..6
R 2
(650 4000);
FORCEPROP 3 LASTPIN (600 4000) SIG_NAME M_D_DQS_DP<5>
J 0
(610 4010);
DISPLAY 0.659574 (610 4010);
PAINT MONO (610 4010);
DISPLAY INVISIBLE (610 4010);
FORCEPROP 1 LASTPIN (600 4000) BN 5
J 2
(650 4010);
DISPLAY 0.617021 (650 4010);
PAINT PINK (650 4010);
FORCEPROP 2 LAST CDS_LIB mstr_standard
J 0
(650 4000);
DISPLAY 0.787234 (650 4000);
PAINT MONO (650 4000);
DISPLAY INVISIBLE (650 4000);
FORCEPROP 1 LAST BODY_TYPE PLUMBING
J 2
(650 3950);
DISPLAY 1.234043 (650 3950);
PAINT GREEN (650 3950);
DISPLAY INVISIBLE (650 3950);
FORCEPROP 1 LAST HDL_TAP TRUE
J 2
(325 3875);
DISPLAY 1.234043 (325 3875);
PAINT GREEN (325 3875);
DISPLAY INVISIBLE (325 3875);
FORCEPROP 1 LAST PATH I35
J 2
(650 4000);
DISPLAY 0.936170 (650 4000);
PAINT GREEN (650 4000);
DISPLAY INVISIBLE (650 4000);
FORCEADD TAP..6
R 2
(650 3800);
FORCEPROP 3 LASTPIN (600 3800) SIG_NAME M_D_DQS_DP<3>
J 0
(610 3810);
DISPLAY 0.659574 (610 3810);
PAINT MONO (610 3810);
DISPLAY INVISIBLE (610 3810);
FORCEPROP 1 LASTPIN (600 3800) BN 3
J 2
(650 3810);
DISPLAY 0.617021 (650 3810);
PAINT PINK (650 3810);
FORCEPROP 2 LAST CDS_LIB mstr_standard
J 0
(650 3800);
DISPLAY 0.787234 (650 3800);
PAINT MONO (650 3800);
DISPLAY INVISIBLE (650 3800);
FORCEPROP 1 LAST BODY_TYPE PLUMBING
J 2
(650 3750);
DISPLAY 1.234043 (650 3750);
PAINT GREEN (650 3750);
DISPLAY INVISIBLE (650 3750);
FORCEPROP 1 LAST HDL_TAP TRUE
J 2
(325 3675);
DISPLAY 1.234043 (325 3675);
PAINT GREEN (325 3675);
DISPLAY INVISIBLE (325 3675);
FORCEPROP 1 LAST PATH I36
J 2
(650 3800);
DISPLAY 0.936170 (650 3800);
PAINT GREEN (650 3800);
DISPLAY INVISIBLE (650 3800);
FORCEADD TAP..6
R 2
(650 3700);
FORCEPROP 3 LASTPIN (600 3700) SIG_NAME M_D_DQS_DP<2>
J 0
(610 3710);
DISPLAY 0.659574 (610 3710);
PAINT MONO (610 3710);
DISPLAY INVISIBLE (610 3710);
FORCEPROP 1 LASTPIN (600 3700) BN 2
J 2
(650 3710);
DISPLAY 0.617021 (650 3710);
PAINT PINK (650 3710);
FORCEPROP 2 LAST CDS_LIB mstr_standard
J 0
(650 3700);
DISPLAY 0.787234 (650 3700);
PAINT MONO (650 3700);
DISPLAY INVISIBLE (650 3700);
FORCEPROP 1 LAST BODY_TYPE PLUMBING
J 2
(650 3650);
DISPLAY 1.234043 (650 3650);
PAINT GREEN (650 3650);
DISPLAY INVISIBLE (650 3650);
FORCEPROP 1 LAST HDL_TAP TRUE
J 2
(325 3575);
DISPLAY 1.234043 (325 3575);
PAINT GREEN (325 3575);
DISPLAY INVISIBLE (325 3575);
FORCEPROP 1 LAST PATH I37
J 2
(650 3700);
DISPLAY 0.936170 (650 3700);
PAINT GREEN (650 3700);
DISPLAY INVISIBLE (650 3700);
FORCEADD TAP..6
R 2
(650 3600);
FORCEPROP 3 LASTPIN (600 3600) SIG_NAME M_D_DQS_DP<1>
J 0
(610 3610);
DISPLAY 0.659574 (610 3610);
PAINT MONO (610 3610);
DISPLAY INVISIBLE (610 3610);
FORCEPROP 1 LASTPIN (600 3600) BN 1
J 2
(650 3610);
DISPLAY 0.617021 (650 3610);
PAINT PINK (650 3610);
FORCEPROP 2 LAST CDS_LIB mstr_standard
J 0
(650 3600);
DISPLAY 0.787234 (650 3600);
PAINT MONO (650 3600);
DISPLAY INVISIBLE (650 3600);
FORCEPROP 1 LAST BODY_TYPE PLUMBING
J 2
(650 3550);
DISPLAY 1.234043 (650 3550);
PAINT GREEN (650 3550);
DISPLAY INVISIBLE (650 3550);
FORCEPROP 1 LAST HDL_TAP TRUE
J 2
(325 3475);
DISPLAY 1.234043 (325 3475);
PAINT GREEN (325 3475);
DISPLAY INVISIBLE (325 3475);
FORCEPROP 1 LAST PATH I38
J 2
(650 3600);
DISPLAY 0.936170 (650 3600);
PAINT GREEN (650 3600);
DISPLAY INVISIBLE (650 3600);
FORCEADD TAP..6
R 2
(900 3450);
FORCEPROP 3 LASTPIN (850 3450) SIG_NAME M_D_DQS_DN<0>
J 0
(860 3460);
DISPLAY 0.659574 (860 3460);
PAINT MONO (860 3460);
DISPLAY INVISIBLE (860 3460);
FORCEPROP 1 LASTPIN (850 3450) BN 0
J 2
(900 3460);
DISPLAY 0.617021 (900 3460);
PAINT PINK (900 3460);
FORCEPROP 2 LAST CDS_LIB mstr_standard
J 0
(900 3450);
DISPLAY 0.787234 (900 3450);
PAINT MONO (900 3450);
DISPLAY INVISIBLE (900 3450);
FORCEPROP 1 LAST BODY_TYPE PLUMBING
J 2
(900 3400);
DISPLAY 1.234043 (900 3400);
PAINT GREEN (900 3400);
DISPLAY INVISIBLE (900 3400);
FORCEPROP 1 LAST HDL_TAP TRUE
J 2
(575 3325);
DISPLAY 1.234043 (575 3325);
PAINT GREEN (575 3325);
DISPLAY INVISIBLE (575 3325);
FORCEPROP 1 LAST PATH I39
J 2
(900 3450);
DISPLAY 0.936170 (900 3450);
PAINT GREEN (900 3450);
DISPLAY INVISIBLE (900 3450);
FORCEADD TAP..6
R 2
(650 5200);
FORCEPROP 3 LASTPIN (600 5200) SIG_NAME M_D_DQS_DP<17>
J 0
(610 5210);
DISPLAY 0.659574 (610 5210);
PAINT MONO (610 5210);
DISPLAY INVISIBLE (610 5210);
FORCEPROP 1 LASTPIN (600 5200) BN 17
J 2
(650 5210);
DISPLAY 0.617021 (650 5210);
PAINT PINK (650 5210);
FORCEPROP 2 LAST CDS_LIB mstr_standard
J 2
(650 5200);
DISPLAY 0.787234 (650 5200);
PAINT MONO (650 5200);
DISPLAY INVISIBLE (650 5200);
FORCEPROP 1 LAST BODY_TYPE PLUMBING
J 2
(650 5150);
DISPLAY 1.234043 (650 5150);
PAINT GREEN (650 5150);
DISPLAY INVISIBLE (650 5150);
FORCEPROP 1 LAST HDL_TAP TRUE
J 2
(325 5075);
DISPLAY 1.234043 (325 5075);
PAINT GREEN (325 5075);
DISPLAY INVISIBLE (325 5075);
FORCEPROP 1 LAST PATH I4
J 2
(650 5200);
DISPLAY 0.936170 (650 5200);
PAINT GREEN (650 5200);
DISPLAY INVISIBLE (650 5200);
FORCEADD TAP..6
R 2
(900 3550);
FORCEPROP 3 LASTPIN (850 3550) SIG_NAME M_D_DQS_DN<1>
J 0
(860 3560);
DISPLAY 0.659574 (860 3560);
PAINT MONO (860 3560);
DISPLAY INVISIBLE (860 3560);
FORCEPROP 1 LASTPIN (850 3550) BN 1
J 2
(900 3560);
DISPLAY 0.617021 (900 3560);
PAINT PINK (900 3560);
FORCEPROP 2 LAST CDS_LIB mstr_standard
J 0
(900 3550);
DISPLAY 0.787234 (900 3550);
PAINT MONO (900 3550);
DISPLAY INVISIBLE (900 3550);
FORCEPROP 1 LAST BODY_TYPE PLUMBING
J 2
(900 3500);
DISPLAY 1.234043 (900 3500);
PAINT GREEN (900 3500);
DISPLAY INVISIBLE (900 3500);
FORCEPROP 1 LAST HDL_TAP TRUE
J 2
(575 3425);
DISPLAY 1.234043 (575 3425);
PAINT GREEN (575 3425);
DISPLAY INVISIBLE (575 3425);
FORCEPROP 1 LAST PATH I40
J 2
(900 3550);
DISPLAY 0.936170 (900 3550);
PAINT GREEN (900 3550);
DISPLAY INVISIBLE (900 3550);
FORCEADD TAP..6
R 2
(650 3500);
FORCEPROP 3 LASTPIN (600 3500) SIG_NAME M_D_DQS_DP<0>
J 0
(610 3510);
DISPLAY 0.659574 (610 3510);
PAINT MONO (610 3510);
DISPLAY INVISIBLE (610 3510);
FORCEPROP 1 LASTPIN (600 3500) BN 0
J 2
(650 3510);
DISPLAY 0.617021 (650 3510);
PAINT PINK (650 3510);
FORCEPROP 2 LAST CDS_LIB mstr_standard
J 0
(650 3500);
DISPLAY 0.787234 (650 3500);
PAINT MONO (650 3500);
DISPLAY INVISIBLE (650 3500);
FORCEPROP 1 LAST BODY_TYPE PLUMBING
J 2
(650 3450);
DISPLAY 1.234043 (650 3450);
PAINT GREEN (650 3450);
DISPLAY INVISIBLE (650 3450);
FORCEPROP 1 LAST HDL_TAP TRUE
J 2
(325 3375);
DISPLAY 1.234043 (325 3375);
PAINT GREEN (325 3375);
DISPLAY INVISIBLE (325 3375);
FORCEPROP 1 LAST PATH I41
J 2
(650 3500);
DISPLAY 0.936170 (650 3500);
PAINT GREEN (650 3500);
DISPLAY INVISIBLE (650 3500);
FORCEADD SCONN288_H44441004..3
(1800 2450);
FORCEPROP 1 LAST LOCATION J4B1
J 0
(1350 3850);
DISPLAY 0.617021 (1350 3850);
PAINT AQUA (1350 3850);
FORCEPROP 1 LAST PART_NUMBER H44441-004
J 0
(1350 1100);
DISPLAY 0.617021 (1350 1100);
PAINT BLUE (1350 1100);
FORCEPROP 1 LAST MATERIAL SCONN
J 0
(1350 3800);
DISPLAY 0.617021 (1350 3800);
PAINT SKYBLUE (1350 3800);
FORCEPROP 2 LASTPIN (1300 3600) $PN 2
J 2
(1290 3610);
DISPLAY 0.617021 (1290 3610);
PAINT ORANGE (1290 3610);
FORCEPROP 2 LASTPIN (1300 3550) $PN 4
J 2
(1290 3560);
DISPLAY 0.617021 (1290 3560);
PAINT ORANGE (1290 3560);
FORCEPROP 2 LASTPIN (1300 3500) $PN 6
J 2
(1290 3510);
DISPLAY 0.617021 (1290 3510);
PAINT ORANGE (1290 3510);
FORCEPROP 2 LASTPIN (1300 3450) $PN 9
J 2
(1290 3460);
DISPLAY 0.617021 (1290 3460);
PAINT ORANGE (1290 3460);
FORCEPROP 2 LASTPIN (1300 3400) $PN 11
J 2
(1290 3410);
DISPLAY 0.617021 (1290 3410);
PAINT ORANGE (1290 3410);
FORCEPROP 2 LASTPIN (1300 3350) $PN 13
J 2
(1290 3360);
DISPLAY 0.617021 (1290 3360);
PAINT ORANGE (1290 3360);
FORCEPROP 2 LASTPIN (1300 3300) $PN 15
J 2
(1290 3310);
DISPLAY 0.617021 (1290 3310);
PAINT ORANGE (1290 3310);
FORCEPROP 2 LASTPIN (1300 3250) $PN 17
J 2
(1290 3260);
DISPLAY 0.617021 (1290 3260);
PAINT ORANGE (1290 3260);
FORCEPROP 2 LASTPIN (1300 3200) $PN 20
J 2
(1290 3210);
DISPLAY 0.617021 (1290 3210);
PAINT ORANGE (1290 3210);
FORCEPROP 2 LASTPIN (1300 3150) $PN 22
J 2
(1290 3160);
DISPLAY 0.617021 (1290 3160);
PAINT ORANGE (1290 3160);
FORCEPROP 2 LASTPIN (1300 3100) $PN 24
J 2
(1290 3110);
DISPLAY 0.617021 (1290 3110);
PAINT ORANGE (1290 3110);
FORCEPROP 2 LASTPIN (1300 3050) $PN 26
J 2
(1290 3060);
DISPLAY 0.617021 (1290 3060);
PAINT ORANGE (1290 3060);
FORCEPROP 2 LASTPIN (1300 3000) $PN 28
J 2
(1290 3010);
DISPLAY 0.617021 (1290 3010);
PAINT ORANGE (1290 3010);
FORCEPROP 2 LASTPIN (1300 2950) $PN 31
J 2
(1290 2960);
DISPLAY 0.617021 (1290 2960);
PAINT ORANGE (1290 2960);
FORCEPROP 2 LASTPIN (1300 2900) $PN 33
J 2
(1290 2910);
DISPLAY 0.617021 (1290 2910);
PAINT ORANGE (1290 2910);
FORCEPROP 2 LASTPIN (1300 2850) $PN 35
J 2
(1290 2860);
DISPLAY 0.617021 (1290 2860);
PAINT ORANGE (1290 2860);
FORCEPROP 2 LASTPIN (1300 2800) $PN 37
J 2
(1290 2810);
DISPLAY 0.617021 (1290 2810);
PAINT ORANGE (1290 2810);
FORCEPROP 2 LASTPIN (1300 2750) $PN 39
J 2
(1290 2760);
DISPLAY 0.617021 (1290 2760);
PAINT ORANGE (1290 2760);
FORCEPROP 2 LASTPIN (1300 2700) $PN 42
J 2
(1290 2710);
DISPLAY 0.617021 (1290 2710);
PAINT ORANGE (1290 2710);
FORCEPROP 2 LASTPIN (1300 2650) $PN 44
J 2
(1290 2660);
DISPLAY 0.617021 (1290 2660);
PAINT ORANGE (1290 2660);
FORCEPROP 2 LASTPIN (1300 2600) $PN 46
J 2
(1290 2610);
DISPLAY 0.617021 (1290 2610);
PAINT ORANGE (1290 2610);
FORCEPROP 2 LASTPIN (1300 2550) $PN 48
J 2
(1290 2560);
DISPLAY 0.617021 (1290 2560);
PAINT ORANGE (1290 2560);
FORCEPROP 2 LASTPIN (1300 2500) $PN 50
J 2
(1290 2510);
DISPLAY 0.617021 (1290 2510);
PAINT ORANGE (1290 2510);
FORCEPROP 2 LASTPIN (1300 2450) $PN 53
J 2
(1290 2460);
DISPLAY 0.617021 (1290 2460);
PAINT ORANGE (1290 2460);
FORCEPROP 2 LASTPIN (1300 2400) $PN 55
J 2
(1290 2410);
DISPLAY 0.617021 (1290 2410);
PAINT ORANGE (1290 2410);
FORCEPROP 2 LASTPIN (1300 2350) $PN 57
J 2
(1290 2360);
DISPLAY 0.617021 (1290 2360);
PAINT ORANGE (1290 2360);
FORCEPROP 2 LASTPIN (1300 2300) $PN 94
J 2
(1290 2310);
DISPLAY 0.617021 (1290 2310);
PAINT ORANGE (1290 2310);
FORCEPROP 2 LASTPIN (1300 2250) $PN 96
J 2
(1290 2260);
DISPLAY 0.617021 (1290 2260);
PAINT ORANGE (1290 2260);
FORCEPROP 2 LASTPIN (1300 2200) $PN 98
J 2
(1290 2210);
DISPLAY 0.617021 (1290 2210);
PAINT ORANGE (1290 2210);
FORCEPROP 2 LASTPIN (1300 2150) $PN 101
J 2
(1290 2160);
DISPLAY 0.617021 (1290 2160);
PAINT ORANGE (1290 2160);
FORCEPROP 2 LASTPIN (1300 2100) $PN 103
J 2
(1290 2110);
DISPLAY 0.617021 (1290 2110);
PAINT ORANGE (1290 2110);
FORCEPROP 2 LASTPIN (1300 2050) $PN 105
J 2
(1290 2060);
DISPLAY 0.617021 (1290 2060);
PAINT ORANGE (1290 2060);
FORCEPROP 2 LASTPIN (1300 2000) $PN 107
J 2
(1290 2010);
DISPLAY 0.617021 (1290 2010);
PAINT ORANGE (1290 2010);
FORCEPROP 2 LASTPIN (1300 1950) $PN 109
J 2
(1290 1960);
DISPLAY 0.617021 (1290 1960);
PAINT ORANGE (1290 1960);
FORCEPROP 2 LASTPIN (1300 1900) $PN 112
J 2
(1290 1910);
DISPLAY 0.617021 (1290 1910);
PAINT ORANGE (1290 1910);
FORCEPROP 2 LASTPIN (1300 1850) $PN 114
J 2
(1290 1860);
DISPLAY 0.617021 (1290 1860);
PAINT ORANGE (1290 1860);
FORCEPROP 2 LASTPIN (1300 1800) $PN 116
J 2
(1290 1810);
DISPLAY 0.617021 (1290 1810);
PAINT ORANGE (1290 1810);
FORCEPROP 2 LASTPIN (1300 1750) $PN 118
J 2
(1290 1760);
DISPLAY 0.617021 (1290 1760);
PAINT ORANGE (1290 1760);
FORCEPROP 2 LASTPIN (1300 1700) $PN 120
J 2
(1290 1710);
DISPLAY 0.617021 (1290 1710);
PAINT ORANGE (1290 1710);
FORCEPROP 2 LASTPIN (1300 1650) $PN 123
J 2
(1290 1660);
DISPLAY 0.617021 (1290 1660);
PAINT ORANGE (1290 1660);
FORCEPROP 2 LASTPIN (1300 1600) $PN 125
J 2
(1290 1610);
DISPLAY 0.617021 (1290 1610);
PAINT ORANGE (1290 1610);
FORCEPROP 2 LASTPIN (1300 1550) $PN 127
J 2
(1290 1560);
DISPLAY 0.617021 (1290 1560);
PAINT ORANGE (1290 1560);
FORCEPROP 2 LASTPIN (1300 1500) $PN 129
J 2
(1290 1510);
DISPLAY 0.617021 (1290 1510);
PAINT ORANGE (1290 1510);
FORCEPROP 2 LASTPIN (1300 1450) $PN 131
J 2
(1290 1460);
DISPLAY 0.617021 (1290 1460);
PAINT ORANGE (1290 1460);
FORCEPROP 2 LASTPIN (1300 1400) $PN 134
J 2
(1290 1410);
DISPLAY 0.617021 (1290 1410);
PAINT ORANGE (1290 1410);
FORCEPROP 2 LASTPIN (1300 1350) $PN 136
J 2
(1290 1360);
DISPLAY 0.617021 (1290 1360);
PAINT ORANGE (1290 1360);
FORCEPROP 2 LASTPIN (1300 1300) $PN 138
J 2
(1290 1310);
DISPLAY 0.617021 (1290 1310);
PAINT ORANGE (1290 1310);
FORCEPROP 2 LASTPIN (2300 3600) $PN 147
J 0
(2310 3610);
DISPLAY 0.617021 (2310 3610);
PAINT ORANGE (2310 3610);
FORCEPROP 2 LASTPIN (2300 3550) $PN 149
J 0
(2310 3560);
DISPLAY 0.617021 (2310 3560);
PAINT ORANGE (2310 3560);
FORCEPROP 2 LASTPIN (2300 3500) $PN 151
J 0
(2310 3510);
DISPLAY 0.617021 (2310 3510);
PAINT ORANGE (2310 3510);
FORCEPROP 2 LASTPIN (2300 3450) $PN 154
J 0
(2310 3460);
DISPLAY 0.617021 (2310 3460);
PAINT ORANGE (2310 3460);
FORCEPROP 2 LASTPIN (2300 3400) $PN 156
J 0
(2310 3410);
DISPLAY 0.617021 (2310 3410);
PAINT ORANGE (2310 3410);
FORCEPROP 2 LASTPIN (2300 3350) $PN 158
J 0
(2310 3360);
DISPLAY 0.617021 (2310 3360);
PAINT ORANGE (2310 3360);
FORCEPROP 2 LASTPIN (2300 3300) $PN 160
J 0
(2310 3310);
DISPLAY 0.617021 (2310 3310);
PAINT ORANGE (2310 3310);
FORCEPROP 2 LASTPIN (2300 3250) $PN 162
J 0
(2310 3260);
DISPLAY 0.617021 (2310 3260);
PAINT ORANGE (2310 3260);
FORCEPROP 2 LASTPIN (2300 3200) $PN 165
J 0
(2310 3210);
DISPLAY 0.617021 (2310 3210);
PAINT ORANGE (2310 3210);
FORCEPROP 2 LASTPIN (2300 3150) $PN 167
J 0
(2310 3160);
DISPLAY 0.617021 (2310 3160);
PAINT ORANGE (2310 3160);
FORCEPROP 2 LASTPIN (2300 3100) $PN 169
J 0
(2310 3110);
DISPLAY 0.617021 (2310 3110);
PAINT ORANGE (2310 3110);
FORCEPROP 2 LASTPIN (2300 3050) $PN 171
J 0
(2310 3060);
DISPLAY 0.617021 (2310 3060);
PAINT ORANGE (2310 3060);
FORCEPROP 2 LASTPIN (2300 3000) $PN 173
J 0
(2310 3010);
DISPLAY 0.617021 (2310 3010);
PAINT ORANGE (2310 3010);
FORCEPROP 2 LASTPIN (2300 2950) $PN 176
J 0
(2310 2960);
DISPLAY 0.617021 (2310 2960);
PAINT ORANGE (2310 2960);
FORCEPROP 2 LASTPIN (2300 2900) $PN 178
J 0
(2310 2910);
DISPLAY 0.617021 (2310 2910);
PAINT ORANGE (2310 2910);
FORCEPROP 2 LASTPIN (2300 2850) $PN 180
J 0
(2310 2860);
DISPLAY 0.617021 (2310 2860);
PAINT ORANGE (2310 2860);
FORCEPROP 2 LASTPIN (2300 2800) $PN 182
J 0
(2310 2810);
DISPLAY 0.617021 (2310 2810);
PAINT ORANGE (2310 2810);
FORCEPROP 2 LASTPIN (2300 2750) $PN 184
J 0
(2310 2760);
DISPLAY 0.617021 (2310 2760);
PAINT ORANGE (2310 2760);
FORCEPROP 2 LASTPIN (2300 2700) $PN 187
J 0
(2310 2710);
DISPLAY 0.617021 (2310 2710);
PAINT ORANGE (2310 2710);
FORCEPROP 2 LASTPIN (2300 2650) $PN 189
J 0
(2310 2660);
DISPLAY 0.617021 (2310 2660);
PAINT ORANGE (2310 2660);
FORCEPROP 2 LASTPIN (2300 2600) $PN 191
J 0
(2310 2610);
DISPLAY 0.617021 (2310 2610);
PAINT ORANGE (2310 2610);
FORCEPROP 2 LASTPIN (2300 2550) $PN 193
J 0
(2310 2560);
DISPLAY 0.617021 (2310 2560);
PAINT ORANGE (2310 2560);
FORCEPROP 2 LASTPIN (2300 2500) $PN 195
J 0
(2310 2510);
DISPLAY 0.617021 (2310 2510);
PAINT ORANGE (2310 2510);
FORCEPROP 2 LASTPIN (2300 2450) $PN 198
J 0
(2310 2460);
DISPLAY 0.617021 (2310 2460);
PAINT ORANGE (2310 2460);
FORCEPROP 2 LASTPIN (2300 2400) $PN 200
J 0
(2310 2410);
DISPLAY 0.617021 (2310 2410);
PAINT ORANGE (2310 2410);
FORCEPROP 2 LASTPIN (2300 2350) $PN 202
J 0
(2310 2360);
DISPLAY 0.617021 (2310 2360);
PAINT ORANGE (2310 2360);
FORCEPROP 2 LASTPIN (2300 2300) $PN 239
J 0
(2310 2310);
DISPLAY 0.617021 (2310 2310);
PAINT ORANGE (2310 2310);
FORCEPROP 2 LASTPIN (2300 2250) $PN 241
J 0
(2310 2260);
DISPLAY 0.617021 (2310 2260);
PAINT ORANGE (2310 2260);
FORCEPROP 2 LASTPIN (2300 2200) $PN 243
J 0
(2310 2210);
DISPLAY 0.617021 (2310 2210);
PAINT ORANGE (2310 2210);
FORCEPROP 2 LASTPIN (2300 2150) $PN 246
J 0
(2310 2160);
DISPLAY 0.617021 (2310 2160);
PAINT ORANGE (2310 2160);
FORCEPROP 2 LASTPIN (2300 2100) $PN 248
J 0
(2310 2110);
DISPLAY 0.617021 (2310 2110);
PAINT ORANGE (2310 2110);
FORCEPROP 2 LASTPIN (2300 2050) $PN 250
J 0
(2310 2060);
DISPLAY 0.617021 (2310 2060);
PAINT ORANGE (2310 2060);
FORCEPROP 2 LASTPIN (2300 2000) $PN 252
J 0
(2310 2010);
DISPLAY 0.617021 (2310 2010);
PAINT ORANGE (2310 2010);
FORCEPROP 2 LASTPIN (2300 1950) $PN 254
J 0
(2310 1960);
DISPLAY 0.617021 (2310 1960);
PAINT ORANGE (2310 1960);
FORCEPROP 2 LASTPIN (2300 1900) $PN 257
J 0
(2310 1910);
DISPLAY 0.617021 (2310 1910);
PAINT ORANGE (2310 1910);
FORCEPROP 2 LASTPIN (2300 1850) $PN 259
J 0
(2310 1860);
DISPLAY 0.617021 (2310 1860);
PAINT ORANGE (2310 1860);
FORCEPROP 2 LASTPIN (2300 1800) $PN 261
J 0
(2310 1810);
DISPLAY 0.617021 (2310 1810);
PAINT ORANGE (2310 1810);
FORCEPROP 2 LASTPIN (2300 1750) $PN 263
J 0
(2310 1760);
DISPLAY 0.617021 (2310 1760);
PAINT ORANGE (2310 1760);
FORCEPROP 2 LASTPIN (2300 1700) $PN 265
J 0
(2310 1710);
DISPLAY 0.617021 (2310 1710);
PAINT ORANGE (2310 1710);
FORCEPROP 2 LASTPIN (2300 1650) $PN 268
J 0
(2310 1660);
DISPLAY 0.617021 (2310 1660);
PAINT ORANGE (2310 1660);
FORCEPROP 2 LASTPIN (2300 1600) $PN 270
J 0
(2310 1610);
DISPLAY 0.617021 (2310 1610);
PAINT ORANGE (2310 1610);
FORCEPROP 2 LASTPIN (2300 1550) $PN 272
J 0
(2310 1560);
DISPLAY 0.617021 (2310 1560);
PAINT ORANGE (2310 1560);
FORCEPROP 2 LASTPIN (2300 1500) $PN 274
J 0
(2310 1510);
DISPLAY 0.617021 (2310 1510);
PAINT ORANGE (2310 1510);
FORCEPROP 2 LASTPIN (2300 1450) $PN 276
J 0
(2310 1460);
DISPLAY 0.617021 (2310 1460);
PAINT ORANGE (2310 1460);
FORCEPROP 2 LASTPIN (2300 1400) $PN 279
J 0
(2310 1410);
DISPLAY 0.617021 (2310 1410);
PAINT ORANGE (2310 1410);
FORCEPROP 2 LASTPIN (2300 1350) $PN 281
J 0
(2310 1360);
DISPLAY 0.617021 (2310 1360);
PAINT ORANGE (2310 1360);
FORCEPROP 2 LASTPIN (2300 1300) $PN 283
J 0
(2310 1310);
DISPLAY 0.617021 (2310 1310);
PAINT ORANGE (2310 1310);
FORCEPROP 1 LAST PACK_TYPE PIP
J 0
(1350 3900);
PAINT SKYBLUE (1350 3900);
DISPLAY INVISIBLE (1350 3900);
FORCEPROP 2 LAST BOM_COST MEM
J 0
(1800 2450);
PAINT ORANGE (1800 2450);
DISPLAY INVISIBLE (1800 2450);
FORCEPROP 2 LAST CDS_LIB mstr_sconn
J 0
(1800 2450);
PAINT ORANGE (1800 2450);
DISPLAY INVISIBLE (1800 2450);
FORCEPROP 2 LAST SEC_TYPE PIP
J 0
(1350 3900);
DISPLAY 1.021277 (1350 3900);
PAINT ORANGE (1350 3900);
DISPLAY INVISIBLE (1350 3900);
FORCEPROP 2 LAST SEC 3
J 0
(1350 3900);
DISPLAY 0.680851 (1350 3900);
PAINT MONO (1350 3900);
DISPLAY INVISIBLE (1350 3900);
FORCEPROP 2 LAST CDS_LOCATION J4B1
J 0
(1350 3850);
DISPLAY 0.617021 (1350 3850);
PAINT AQUA (1350 3850);
DISPLAY INVISIBLE (1350 3850);
FORCEPROP 1 LAST PATH I43
J 0
(1800 3800);
PAINT GREEN (1800 3800);
DISPLAY INVISIBLE (1800 3800);
FORCEPROP 2 LAST ROOM DDR4_CH_D
J 0
(1800 2450);
PAINT ORANGE (1800 2450);
DISPLAY INVISIBLE (1800 2450);
FORCEADD GND..1
R 2
(1100 1150);
FORCEPROP 3 LASTPIN (1100 1200) SIG_NAME GND\g
J 0
(1110 1210);
DISPLAY 0.659574 (1110 1210);
PAINT MONO (1110 1210);
DISPLAY INVISIBLE (1110 1210);
FORCEPROP 1 LAST VOLTAGE 0
J 0
(1100 1150);
PAINT SKYBLUE (1100 1150);
DISPLAY INVISIBLE (1100 1150);
FORCEPROP 1 LAST SIZE 1B
J 2
(1025 1100);
DISPLAY 1.170213 (1025 1100);
PAINT GREEN (1025 1100);
DISPLAY INVISIBLE (1025 1100);
FORCEPROP 2 LAST CDS_LIB mstr_symbols
J 0
(1100 1150);
DISPLAY 0.787234 (1100 1150);
PAINT MONO (1100 1150);
DISPLAY INVISIBLE (1100 1150);
FORCEPROP 2 LAST BOM_COST MEM
J 0
(1100 1155);
PAINT ORANGE (1100 1155);
DISPLAY INVISIBLE (1100 1155);
FORCEPROP 1 LAST BODY_TYPE PLUMBING
J 2
(1145 1107);
DISPLAY 0.340426 (1145 1107);
PAINT GREEN (1145 1107);
DISPLAY INVISIBLE (1145 1107);
FORCEPROP 1 LAST PATH I44
J 2
(1025 1150);
DISPLAY 0.936170 (1025 1150);
PAINT GREEN (1025 1150);
DISPLAY INVISIBLE (1025 1150);
FORCEPROP 2 LAST ROOM DDR4_CH_B
J 0
(1100 1155);
PAINT ORANGE (1100 1155);
DISPLAY INVISIBLE (1100 1155);
FORCEPROP 1 LAST HDL_POWER GND
J 2
(1100 1300);
DISPLAY 0.553191 (1100 1300);
PAINT GREEN (1100 1300);
DISPLAY INVISIBLE (1100 1300);
FORCEADD OFFPAGE..3
(-1200 5200);
FORCEPROP 2 LAST $XR0 26 
J 0
(-986 5200);
DISPLAY 0.638298 (-986 5200);
PAINT MONO (-986 5200);
FORCEPROP 2 LAST $XR1 50 
J 0
(-896 5200);
DISPLAY 0.638298 (-896 5200);
PAINT MONO (-896 5200);
FORCEPROP 2 LAST CDS_LIB mstr_standard
J 0
(-1200 5200);
DISPLAY 0.787234 (-1200 5200);
PAINT MONO (-1200 5200);
DISPLAY INVISIBLE (-1200 5200);
FORCEPROP 1 LAST OFFPAGE TRUE
J 0
(-875 5075);
DISPLAY 0.936170 (-875 5075);
PAINT GREEN (-875 5075);
DISPLAY INVISIBLE (-875 5075);
FORCEPROP 1 LAST COMMENT_BODY TRUE
J 0
(-1250 5100);
DISPLAY 0.936170 (-1250 5100);
PAINT GREEN (-1250 5100);
DISPLAY INVISIBLE (-1250 5100);
FORCEPROP 2 LAST PATH I45
J 0
(-1000 5275);
DISPLAY 0.787234 (-1000 5275);
PAINT MONO (-1000 5275);
DISPLAY INVISIBLE (-1000 5275);
FORCEADD TAP..6
R 2
(-1750 5150);
FORCEPROP 3 LASTPIN (-1800 5150) SIG_NAME M_D_DQ<62>
J 0
(-1790 5160);
DISPLAY 0.659574 (-1790 5160);
PAINT MONO (-1790 5160);
DISPLAY INVISIBLE (-1790 5160);
FORCEPROP 1 LASTPIN (-1800 5150) BN 62
J 2
(-1750 5160);
DISPLAY 0.617021 (-1750 5160);
PAINT PINK (-1750 5160);
FORCEPROP 2 LAST CDS_LIB mstr_standard
J 2
(-1750 5150);
DISPLAY 0.787234 (-1750 5150);
PAINT MONO (-1750 5150);
DISPLAY INVISIBLE (-1750 5150);
FORCEPROP 1 LAST BODY_TYPE PLUMBING
J 2
(-1750 5100);
DISPLAY 1.234043 (-1750 5100);
PAINT GREEN (-1750 5100);
DISPLAY INVISIBLE (-1750 5100);
FORCEPROP 1 LAST HDL_TAP TRUE
J 2
(-2075 5025);
DISPLAY 1.234043 (-2075 5025);
PAINT GREEN (-2075 5025);
DISPLAY INVISIBLE (-2075 5025);
FORCEPROP 1 LAST PATH I46
J 2
(-1750 5150);
DISPLAY 0.936170 (-1750 5150);
PAINT GREEN (-1750 5150);
DISPLAY INVISIBLE (-1750 5150);
FORCEADD TAP..6
R 2
(-1750 5100);
FORCEPROP 3 LASTPIN (-1800 5100) SIG_NAME M_D_DQ<63>
J 0
(-1790 5110);
DISPLAY 0.659574 (-1790 5110);
PAINT MONO (-1790 5110);
DISPLAY INVISIBLE (-1790 5110);
FORCEPROP 1 LASTPIN (-1800 5100) BN 63
J 2
(-1750 5110);
DISPLAY 0.617021 (-1750 5110);
PAINT PINK (-1750 5110);
FORCEPROP 2 LAST CDS_LIB mstr_standard
J 2
(-1750 5100);
DISPLAY 0.787234 (-1750 5100);
PAINT MONO (-1750 5100);
DISPLAY INVISIBLE (-1750 5100);
FORCEPROP 1 LAST BODY_TYPE PLUMBING
J 2
(-1750 5050);
DISPLAY 1.234043 (-1750 5050);
PAINT GREEN (-1750 5050);
DISPLAY INVISIBLE (-1750 5050);
FORCEPROP 1 LAST HDL_TAP TRUE
J 2
(-2075 4975);
DISPLAY 1.234043 (-2075 4975);
PAINT GREEN (-2075 4975);
DISPLAY INVISIBLE (-2075 4975);
FORCEPROP 1 LAST PATH I47
J 2
(-1750 5100);
DISPLAY 0.936170 (-1750 5100);
PAINT GREEN (-1750 5100);
DISPLAY INVISIBLE (-1750 5100);
FORCEADD TAP..6
R 2
(-1750 5000);
FORCEPROP 3 LASTPIN (-1800 5000) SIG_NAME M_D_DQ<61>
J 0
(-1790 5010);
DISPLAY 0.659574 (-1790 5010);
PAINT MONO (-1790 5010);
DISPLAY INVISIBLE (-1790 5010);
FORCEPROP 1 LASTPIN (-1800 5000) BN 61
J 2
(-1750 5010);
DISPLAY 0.617021 (-1750 5010);
PAINT PINK (-1750 5010);
FORCEPROP 2 LAST CDS_LIB mstr_standard
J 2
(-1750 5000);
DISPLAY 0.787234 (-1750 5000);
PAINT MONO (-1750 5000);
DISPLAY INVISIBLE (-1750 5000);
FORCEPROP 1 LAST BODY_TYPE PLUMBING
J 2
(-1750 4950);
DISPLAY 1.234043 (-1750 4950);
PAINT GREEN (-1750 4950);
DISPLAY INVISIBLE (-1750 4950);
FORCEPROP 1 LAST HDL_TAP TRUE
J 2
(-2075 4875);
DISPLAY 1.234043 (-2075 4875);
PAINT GREEN (-2075 4875);
DISPLAY INVISIBLE (-2075 4875);
FORCEPROP 1 LAST PATH I48
J 2
(-1750 5000);
DISPLAY 0.936170 (-1750 5000);
PAINT GREEN (-1750 5000);
DISPLAY INVISIBLE (-1750 5000);
FORCEADD TAP..6
R 2
(-1750 5050);
FORCEPROP 3 LASTPIN (-1800 5050) SIG_NAME M_D_DQ<60>
J 0
(-1790 5060);
DISPLAY 0.659574 (-1790 5060);
PAINT MONO (-1790 5060);
DISPLAY INVISIBLE (-1790 5060);
FORCEPROP 1 LASTPIN (-1800 5050) BN 60
J 2
(-1750 5060);
DISPLAY 0.617021 (-1750 5060);
PAINT PINK (-1750 5060);
FORCEPROP 2 LAST CDS_LIB mstr_standard
J 2
(-1750 5050);
DISPLAY 0.787234 (-1750 5050);
PAINT MONO (-1750 5050);
DISPLAY INVISIBLE (-1750 5050);
FORCEPROP 1 LAST BODY_TYPE PLUMBING
J 2
(-1750 5000);
DISPLAY 1.234043 (-1750 5000);
PAINT GREEN (-1750 5000);
DISPLAY INVISIBLE (-1750 5000);
FORCEPROP 1 LAST HDL_TAP TRUE
J 2
(-2075 4925);
DISPLAY 1.234043 (-2075 4925);
PAINT GREEN (-2075 4925);
DISPLAY INVISIBLE (-2075 4925);
FORCEPROP 1 LAST PATH I49
J 2
(-1750 5050);
DISPLAY 0.936170 (-1750 5050);
PAINT GREEN (-1750 5050);
DISPLAY INVISIBLE (-1750 5050);
FORCEADD TAP..6
R 2
(900 5050);
FORCEPROP 3 LASTPIN (850 5050) SIG_NAME M_D_DQS_DN<16>
J 0
(860 5060);
DISPLAY 0.659574 (860 5060);
PAINT MONO (860 5060);
DISPLAY INVISIBLE (860 5060);
FORCEPROP 1 LASTPIN (850 5050) BN 16
J 2
(900 5060);
DISPLAY 0.617021 (900 5060);
PAINT PINK (900 5060);
FORCEPROP 2 LAST CDS_LIB mstr_standard
J 0
(900 5050);
DISPLAY 0.787234 (900 5050);
PAINT MONO (900 5050);
DISPLAY INVISIBLE (900 5050);
FORCEPROP 1 LAST BODY_TYPE PLUMBING
J 2
(900 5000);
DISPLAY 1.234043 (900 5000);
PAINT GREEN (900 5000);
DISPLAY INVISIBLE (900 5000);
FORCEPROP 1 LAST HDL_TAP TRUE
J 2
(575 4925);
DISPLAY 1.234043 (575 4925);
PAINT GREEN (575 4925);
DISPLAY INVISIBLE (575 4925);
FORCEPROP 1 LAST PATH I5
J 2
(900 5050);
DISPLAY 0.936170 (900 5050);
PAINT GREEN (900 5050);
DISPLAY INVISIBLE (900 5050);
FORCEADD TAP..6
R 2
(-1750 4950);
FORCEPROP 3 LASTPIN (-1800 4950) SIG_NAME M_D_DQ<58>
J 0
(-1790 4960);
DISPLAY 0.659574 (-1790 4960);
PAINT MONO (-1790 4960);
DISPLAY INVISIBLE (-1790 4960);
FORCEPROP 1 LASTPIN (-1800 4950) BN 58
J 2
(-1750 4960);
DISPLAY 0.617021 (-1750 4960);
PAINT PINK (-1750 4960);
FORCEPROP 2 LAST CDS_LIB mstr_standard
J 2
(-1750 4950);
DISPLAY 0.787234 (-1750 4950);
PAINT MONO (-1750 4950);
DISPLAY INVISIBLE (-1750 4950);
FORCEPROP 1 LAST BODY_TYPE PLUMBING
J 2
(-1750 4900);
DISPLAY 1.234043 (-1750 4900);
PAINT GREEN (-1750 4900);
DISPLAY INVISIBLE (-1750 4900);
FORCEPROP 1 LAST HDL_TAP TRUE
J 2
(-2075 4825);
DISPLAY 1.234043 (-2075 4825);
PAINT GREEN (-2075 4825);
DISPLAY INVISIBLE (-2075 4825);
FORCEPROP 1 LAST PATH I50
J 2
(-1750 4950);
DISPLAY 0.936170 (-1750 4950);
PAINT GREEN (-1750 4950);
DISPLAY INVISIBLE (-1750 4950);
FORCEADD TAP..6
R 2
(-1750 4850);
FORCEPROP 3 LASTPIN (-1800 4850) SIG_NAME M_D_DQ<56>
J 0
(-1790 4860);
DISPLAY 0.659574 (-1790 4860);
PAINT MONO (-1790 4860);
DISPLAY INVISIBLE (-1790 4860);
FORCEPROP 1 LASTPIN (-1800 4850) BN 56
J 2
(-1750 4860);
DISPLAY 0.617021 (-1750 4860);
PAINT PINK (-1750 4860);
FORCEPROP 2 LAST CDS_LIB mstr_standard
J 2
(-1750 4850);
DISPLAY 0.787234 (-1750 4850);
PAINT MONO (-1750 4850);
DISPLAY INVISIBLE (-1750 4850);
FORCEPROP 1 LAST BODY_TYPE PLUMBING
J 2
(-1750 4800);
DISPLAY 1.234043 (-1750 4800);
PAINT GREEN (-1750 4800);
DISPLAY INVISIBLE (-1750 4800);
FORCEPROP 1 LAST HDL_TAP TRUE
J 2
(-2075 4725);
DISPLAY 1.234043 (-2075 4725);
PAINT GREEN (-2075 4725);
DISPLAY INVISIBLE (-2075 4725);
FORCEPROP 1 LAST PATH I51
J 2
(-1750 4850);
DISPLAY 0.936170 (-1750 4850);
PAINT GREEN (-1750 4850);
DISPLAY INVISIBLE (-1750 4850);
FORCEADD TAP..6
R 2
(-1750 4900);
FORCEPROP 3 LASTPIN (-1800 4900) SIG_NAME M_D_DQ<59>
J 0
(-1790 4910);
DISPLAY 0.659574 (-1790 4910);
PAINT MONO (-1790 4910);
DISPLAY INVISIBLE (-1790 4910);
FORCEPROP 1 LASTPIN (-1800 4900) BN 59
J 2
(-1750 4910);
DISPLAY 0.617021 (-1750 4910);
PAINT PINK (-1750 4910);
FORCEPROP 2 LAST CDS_LIB mstr_standard
J 2
(-1750 4900);
DISPLAY 0.787234 (-1750 4900);
PAINT MONO (-1750 4900);
DISPLAY INVISIBLE (-1750 4900);
FORCEPROP 1 LAST BODY_TYPE PLUMBING
J 2
(-1750 4850);
DISPLAY 1.234043 (-1750 4850);
PAINT GREEN (-1750 4850);
DISPLAY INVISIBLE (-1750 4850);
FORCEPROP 1 LAST HDL_TAP TRUE
J 2
(-2075 4775);
DISPLAY 1.234043 (-2075 4775);
PAINT GREEN (-2075 4775);
DISPLAY INVISIBLE (-2075 4775);
FORCEPROP 1 LAST PATH I52
J 2
(-1750 4900);
DISPLAY 0.936170 (-1750 4900);
PAINT GREEN (-1750 4900);
DISPLAY INVISIBLE (-1750 4900);
FORCEADD TAP..6
R 2
(-1750 4800);
FORCEPROP 3 LASTPIN (-1800 4800) SIG_NAME M_D_DQ<57>
J 0
(-1790 4810);
DISPLAY 0.659574 (-1790 4810);
PAINT MONO (-1790 4810);
DISPLAY INVISIBLE (-1790 4810);
FORCEPROP 1 LASTPIN (-1800 4800) BN 57
J 2
(-1750 4810);
DISPLAY 0.617021 (-1750 4810);
PAINT PINK (-1750 4810);
FORCEPROP 2 LAST CDS_LIB mstr_standard
J 2
(-1750 4800);
DISPLAY 0.787234 (-1750 4800);
PAINT MONO (-1750 4800);
DISPLAY INVISIBLE (-1750 4800);
FORCEPROP 1 LAST BODY_TYPE PLUMBING
J 2
(-1750 4750);
DISPLAY 1.234043 (-1750 4750);
PAINT GREEN (-1750 4750);
DISPLAY INVISIBLE (-1750 4750);
FORCEPROP 1 LAST HDL_TAP TRUE
J 2
(-2075 4675);
DISPLAY 1.234043 (-2075 4675);
PAINT GREEN (-2075 4675);
DISPLAY INVISIBLE (-2075 4675);
FORCEPROP 1 LAST PATH I53
J 2
(-1750 4800);
DISPLAY 0.936170 (-1750 4800);
PAINT GREEN (-1750 4800);
DISPLAY INVISIBLE (-1750 4800);
FORCEADD TAP..6
R 2
(-1750 4750);
FORCEPROP 3 LASTPIN (-1800 4750) SIG_NAME M_D_DQ<54>
J 0
(-1790 4760);
DISPLAY 0.659574 (-1790 4760);
PAINT MONO (-1790 4760);
DISPLAY INVISIBLE (-1790 4760);
FORCEPROP 1 LASTPIN (-1800 4750) BN 54
J 2
(-1750 4760);
DISPLAY 0.617021 (-1750 4760);
PAINT PINK (-1750 4760);
FORCEPROP 2 LAST CDS_LIB mstr_standard
J 2
(-1750 4750);
DISPLAY 0.787234 (-1750 4750);
PAINT MONO (-1750 4750);
DISPLAY INVISIBLE (-1750 4750);
FORCEPROP 1 LAST BODY_TYPE PLUMBING
J 2
(-1750 4700);
DISPLAY 1.234043 (-1750 4700);
PAINT GREEN (-1750 4700);
DISPLAY INVISIBLE (-1750 4700);
FORCEPROP 1 LAST HDL_TAP TRUE
J 2
(-2075 4625);
DISPLAY 1.234043 (-2075 4625);
PAINT GREEN (-2075 4625);
DISPLAY INVISIBLE (-2075 4625);
FORCEPROP 1 LAST PATH I54
J 2
(-1750 4750);
DISPLAY 0.936170 (-1750 4750);
PAINT GREEN (-1750 4750);
DISPLAY INVISIBLE (-1750 4750);
FORCEADD TAP..6
R 2
(-1750 4650);
FORCEPROP 3 LASTPIN (-1800 4650) SIG_NAME M_D_DQ<52>
J 0
(-1790 4660);
DISPLAY 0.659574 (-1790 4660);
PAINT MONO (-1790 4660);
DISPLAY INVISIBLE (-1790 4660);
FORCEPROP 1 LASTPIN (-1800 4650) BN 52
J 2
(-1750 4660);
DISPLAY 0.617021 (-1750 4660);
PAINT PINK (-1750 4660);
FORCEPROP 2 LAST CDS_LIB mstr_standard
J 2
(-1750 4650);
DISPLAY 0.787234 (-1750 4650);
PAINT MONO (-1750 4650);
DISPLAY INVISIBLE (-1750 4650);
FORCEPROP 1 LAST BODY_TYPE PLUMBING
J 2
(-1750 4600);
DISPLAY 1.234043 (-1750 4600);
PAINT GREEN (-1750 4600);
DISPLAY INVISIBLE (-1750 4600);
FORCEPROP 1 LAST HDL_TAP TRUE
J 2
(-2075 4525);
DISPLAY 1.234043 (-2075 4525);
PAINT GREEN (-2075 4525);
DISPLAY INVISIBLE (-2075 4525);
FORCEPROP 1 LAST PATH I55
J 2
(-1750 4650);
DISPLAY 0.936170 (-1750 4650);
PAINT GREEN (-1750 4650);
DISPLAY INVISIBLE (-1750 4650);
FORCEADD TAP..6
R 2
(-1750 4700);
FORCEPROP 3 LASTPIN (-1800 4700) SIG_NAME M_D_DQ<55>
J 0
(-1790 4710);
DISPLAY 0.659574 (-1790 4710);
PAINT MONO (-1790 4710);
DISPLAY INVISIBLE (-1790 4710);
FORCEPROP 1 LASTPIN (-1800 4700) BN 55
J 2
(-1750 4710);
DISPLAY 0.617021 (-1750 4710);
PAINT PINK (-1750 4710);
FORCEPROP 2 LAST CDS_LIB mstr_standard
J 2
(-1750 4700);
DISPLAY 0.787234 (-1750 4700);
PAINT MONO (-1750 4700);
DISPLAY INVISIBLE (-1750 4700);
FORCEPROP 1 LAST BODY_TYPE PLUMBING
J 2
(-1750 4650);
DISPLAY 1.234043 (-1750 4650);
PAINT GREEN (-1750 4650);
DISPLAY INVISIBLE (-1750 4650);
FORCEPROP 1 LAST HDL_TAP TRUE
J 2
(-2075 4575);
DISPLAY 1.234043 (-2075 4575);
PAINT GREEN (-2075 4575);
DISPLAY INVISIBLE (-2075 4575);
FORCEPROP 1 LAST PATH I56
J 2
(-1750 4700);
DISPLAY 0.936170 (-1750 4700);
PAINT GREEN (-1750 4700);
DISPLAY INVISIBLE (-1750 4700);
FORCEADD TAP..6
R 2
(-1750 4600);
FORCEPROP 3 LASTPIN (-1800 4600) SIG_NAME M_D_DQ<53>
J 0
(-1790 4610);
DISPLAY 0.659574 (-1790 4610);
PAINT MONO (-1790 4610);
DISPLAY INVISIBLE (-1790 4610);
FORCEPROP 1 LASTPIN (-1800 4600) BN 53
J 2
(-1750 4610);
DISPLAY 0.617021 (-1750 4610);
PAINT PINK (-1750 4610);
FORCEPROP 2 LAST CDS_LIB mstr_standard
J 2
(-1750 4600);
DISPLAY 0.787234 (-1750 4600);
PAINT MONO (-1750 4600);
DISPLAY INVISIBLE (-1750 4600);
FORCEPROP 1 LAST BODY_TYPE PLUMBING
J 2
(-1750 4550);
DISPLAY 1.234043 (-1750 4550);
PAINT GREEN (-1750 4550);
DISPLAY INVISIBLE (-1750 4550);
FORCEPROP 1 LAST HDL_TAP TRUE
J 2
(-2075 4475);
DISPLAY 1.234043 (-2075 4475);
PAINT GREEN (-2075 4475);
DISPLAY INVISIBLE (-2075 4475);
FORCEPROP 1 LAST PATH I57
J 2
(-1750 4600);
DISPLAY 0.936170 (-1750 4600);
PAINT GREEN (-1750 4600);
DISPLAY INVISIBLE (-1750 4600);
FORCEADD TAP..6
R 2
(-1750 4550);
FORCEPROP 3 LASTPIN (-1800 4550) SIG_NAME M_D_DQ<50>
J 0
(-1790 4560);
DISPLAY 0.659574 (-1790 4560);
PAINT MONO (-1790 4560);
DISPLAY INVISIBLE (-1790 4560);
FORCEPROP 1 LASTPIN (-1800 4550) BN 50
J 2
(-1750 4560);
DISPLAY 0.617021 (-1750 4560);
PAINT PINK (-1750 4560);
FORCEPROP 2 LAST CDS_LIB mstr_standard
J 2
(-1750 4550);
DISPLAY 0.787234 (-1750 4550);
PAINT MONO (-1750 4550);
DISPLAY INVISIBLE (-1750 4550);
FORCEPROP 1 LAST BODY_TYPE PLUMBING
J 2
(-1750 4500);
DISPLAY 1.234043 (-1750 4500);
PAINT GREEN (-1750 4500);
DISPLAY INVISIBLE (-1750 4500);
FORCEPROP 1 LAST HDL_TAP TRUE
J 2
(-2075 4425);
DISPLAY 1.234043 (-2075 4425);
PAINT GREEN (-2075 4425);
DISPLAY INVISIBLE (-2075 4425);
FORCEPROP 1 LAST PATH I58
J 2
(-1750 4550);
DISPLAY 0.936170 (-1750 4550);
PAINT GREEN (-1750 4550);
DISPLAY INVISIBLE (-1750 4550);
FORCEADD TAP..6
R 2
(-1750 4500);
FORCEPROP 3 LASTPIN (-1800 4500) SIG_NAME M_D_DQ<51>
J 0
(-1790 4510);
DISPLAY 0.659574 (-1790 4510);
PAINT MONO (-1790 4510);
DISPLAY INVISIBLE (-1790 4510);
FORCEPROP 1 LASTPIN (-1800 4500) BN 51
J 2
(-1750 4510);
DISPLAY 0.617021 (-1750 4510);
PAINT PINK (-1750 4510);
FORCEPROP 2 LAST CDS_LIB mstr_standard
J 2
(-1750 4500);
DISPLAY 0.787234 (-1750 4500);
PAINT MONO (-1750 4500);
DISPLAY INVISIBLE (-1750 4500);
FORCEPROP 1 LAST BODY_TYPE PLUMBING
J 2
(-1750 4450);
DISPLAY 1.234043 (-1750 4450);
PAINT GREEN (-1750 4450);
DISPLAY INVISIBLE (-1750 4450);
FORCEPROP 1 LAST HDL_TAP TRUE
J 2
(-2075 4375);
DISPLAY 1.234043 (-2075 4375);
PAINT GREEN (-2075 4375);
DISPLAY INVISIBLE (-2075 4375);
FORCEPROP 1 LAST PATH I59
J 2
(-1750 4500);
DISPLAY 0.936170 (-1750 4500);
PAINT GREEN (-1750 4500);
DISPLAY INVISIBLE (-1750 4500);
FORCEADD TAP..6
R 2
(900 4950);
FORCEPROP 3 LASTPIN (850 4950) SIG_NAME M_D_DQS_DN<15>
J 0
(860 4960);
DISPLAY 0.659574 (860 4960);
PAINT MONO (860 4960);
DISPLAY INVISIBLE (860 4960);
FORCEPROP 1 LASTPIN (850 4950) BN 15
J 2
(900 4960);
DISPLAY 0.617021 (900 4960);
PAINT PINK (900 4960);
FORCEPROP 2 LAST CDS_LIB mstr_standard
J 0
(900 4950);
DISPLAY 0.787234 (900 4950);
PAINT MONO (900 4950);
DISPLAY INVISIBLE (900 4950);
FORCEPROP 1 LAST BODY_TYPE PLUMBING
J 2
(900 4900);
DISPLAY 1.234043 (900 4900);
PAINT GREEN (900 4900);
DISPLAY INVISIBLE (900 4900);
FORCEPROP 1 LAST HDL_TAP TRUE
J 2
(575 4825);
DISPLAY 1.234043 (575 4825);
PAINT GREEN (575 4825);
DISPLAY INVISIBLE (575 4825);
FORCEPROP 1 LAST PATH I6
J 2
(900 4950);
DISPLAY 0.936170 (900 4950);
PAINT GREEN (900 4950);
DISPLAY INVISIBLE (900 4950);
FORCEADD TAP..6
R 2
(-1750 4450);
FORCEPROP 3 LASTPIN (-1800 4450) SIG_NAME M_D_DQ<48>
J 0
(-1790 4460);
DISPLAY 0.659574 (-1790 4460);
PAINT MONO (-1790 4460);
DISPLAY INVISIBLE (-1790 4460);
FORCEPROP 1 LASTPIN (-1800 4450) BN 48
J 2
(-1750 4460);
DISPLAY 0.617021 (-1750 4460);
PAINT PINK (-1750 4460);
FORCEPROP 2 LAST CDS_LIB mstr_standard
J 2
(-1750 4450);
DISPLAY 0.787234 (-1750 4450);
PAINT MONO (-1750 4450);
DISPLAY INVISIBLE (-1750 4450);
FORCEPROP 1 LAST BODY_TYPE PLUMBING
J 2
(-1750 4400);
DISPLAY 1.234043 (-1750 4400);
PAINT GREEN (-1750 4400);
DISPLAY INVISIBLE (-1750 4400);
FORCEPROP 1 LAST HDL_TAP TRUE
J 2
(-2075 4325);
DISPLAY 1.234043 (-2075 4325);
PAINT GREEN (-2075 4325);
DISPLAY INVISIBLE (-2075 4325);
FORCEPROP 1 LAST PATH I60
J 2
(-1750 4450);
DISPLAY 0.936170 (-1750 4450);
PAINT GREEN (-1750 4450);
DISPLAY INVISIBLE (-1750 4450);
FORCEADD TAP..6
R 2
(-1750 4350);
FORCEPROP 3 LASTPIN (-1800 4350) SIG_NAME M_D_DQ<46>
J 0
(-1790 4360);
DISPLAY 0.659574 (-1790 4360);
PAINT MONO (-1790 4360);
DISPLAY INVISIBLE (-1790 4360);
FORCEPROP 1 LASTPIN (-1800 4350) BN 46
J 2
(-1750 4360);
DISPLAY 0.617021 (-1750 4360);
PAINT PINK (-1750 4360);
FORCEPROP 2 LAST CDS_LIB mstr_standard
J 2
(-1750 4350);
DISPLAY 0.787234 (-1750 4350);
PAINT MONO (-1750 4350);
DISPLAY INVISIBLE (-1750 4350);
FORCEPROP 1 LAST BODY_TYPE PLUMBING
J 2
(-1750 4300);
DISPLAY 1.234043 (-1750 4300);
PAINT GREEN (-1750 4300);
DISPLAY INVISIBLE (-1750 4300);
FORCEPROP 1 LAST HDL_TAP TRUE
J 2
(-2075 4225);
DISPLAY 1.234043 (-2075 4225);
PAINT GREEN (-2075 4225);
DISPLAY INVISIBLE (-2075 4225);
FORCEPROP 1 LAST PATH I61
J 2
(-1750 4350);
DISPLAY 0.936170 (-1750 4350);
PAINT GREEN (-1750 4350);
DISPLAY INVISIBLE (-1750 4350);
FORCEADD TAP..6
R 2
(-1750 4400);
FORCEPROP 3 LASTPIN (-1800 4400) SIG_NAME M_D_DQ<49>
J 0
(-1790 4410);
DISPLAY 0.659574 (-1790 4410);
PAINT MONO (-1790 4410);
DISPLAY INVISIBLE (-1790 4410);
FORCEPROP 1 LASTPIN (-1800 4400) BN 49
J 2
(-1750 4410);
DISPLAY 0.617021 (-1750 4410);
PAINT PINK (-1750 4410);
FORCEPROP 2 LAST CDS_LIB mstr_standard
J 2
(-1750 4400);
DISPLAY 0.787234 (-1750 4400);
PAINT MONO (-1750 4400);
DISPLAY INVISIBLE (-1750 4400);
FORCEPROP 1 LAST BODY_TYPE PLUMBING
J 2
(-1750 4350);
DISPLAY 1.234043 (-1750 4350);
PAINT GREEN (-1750 4350);
DISPLAY INVISIBLE (-1750 4350);
FORCEPROP 1 LAST HDL_TAP TRUE
J 2
(-2075 4275);
DISPLAY 1.234043 (-2075 4275);
PAINT GREEN (-2075 4275);
DISPLAY INVISIBLE (-2075 4275);
FORCEPROP 1 LAST PATH I62
J 2
(-1750 4400);
DISPLAY 0.936170 (-1750 4400);
PAINT GREEN (-1750 4400);
DISPLAY INVISIBLE (-1750 4400);
FORCEADD TAP..6
R 2
(-1750 4300);
FORCEPROP 3 LASTPIN (-1800 4300) SIG_NAME M_D_DQ<47>
J 0
(-1790 4310);
DISPLAY 0.659574 (-1790 4310);
PAINT MONO (-1790 4310);
DISPLAY INVISIBLE (-1790 4310);
FORCEPROP 1 LASTPIN (-1800 4300) BN 47
J 2
(-1750 4310);
DISPLAY 0.617021 (-1750 4310);
PAINT PINK (-1750 4310);
FORCEPROP 2 LAST CDS_LIB mstr_standard
J 2
(-1750 4300);
DISPLAY 0.787234 (-1750 4300);
PAINT MONO (-1750 4300);
DISPLAY INVISIBLE (-1750 4300);
FORCEPROP 1 LAST BODY_TYPE PLUMBING
J 2
(-1750 4250);
DISPLAY 1.234043 (-1750 4250);
PAINT GREEN (-1750 4250);
DISPLAY INVISIBLE (-1750 4250);
FORCEPROP 1 LAST HDL_TAP TRUE
J 2
(-2075 4175);
DISPLAY 1.234043 (-2075 4175);
PAINT GREEN (-2075 4175);
DISPLAY INVISIBLE (-2075 4175);
FORCEPROP 1 LAST PATH I63
J 2
(-1750 4300);
DISPLAY 0.936170 (-1750 4300);
PAINT GREEN (-1750 4300);
DISPLAY INVISIBLE (-1750 4300);
FORCEADD TAP..6
R 2
(-1750 4250);
FORCEPROP 3 LASTPIN (-1800 4250) SIG_NAME M_D_DQ<44>
J 0
(-1790 4260);
DISPLAY 0.659574 (-1790 4260);
PAINT MONO (-1790 4260);
DISPLAY INVISIBLE (-1790 4260);
FORCEPROP 1 LASTPIN (-1800 4250) BN 44
J 2
(-1750 4260);
DISPLAY 0.617021 (-1750 4260);
PAINT PINK (-1750 4260);
FORCEPROP 2 LAST CDS_LIB mstr_standard
J 2
(-1750 4250);
DISPLAY 0.787234 (-1750 4250);
PAINT MONO (-1750 4250);
DISPLAY INVISIBLE (-1750 4250);
FORCEPROP 1 LAST BODY_TYPE PLUMBING
J 2
(-1750 4200);
DISPLAY 1.234043 (-1750 4200);
PAINT GREEN (-1750 4200);
DISPLAY INVISIBLE (-1750 4200);
FORCEPROP 1 LAST HDL_TAP TRUE
J 2
(-2075 4125);
DISPLAY 1.234043 (-2075 4125);
PAINT GREEN (-2075 4125);
DISPLAY INVISIBLE (-2075 4125);
FORCEPROP 1 LAST PATH I64
J 2
(-1750 4250);
DISPLAY 0.936170 (-1750 4250);
PAINT GREEN (-1750 4250);
DISPLAY INVISIBLE (-1750 4250);
FORCEADD TAP..6
R 2
(-1750 4200);
FORCEPROP 3 LASTPIN (-1800 4200) SIG_NAME M_D_DQ<45>
J 0
(-1790 4210);
DISPLAY 0.659574 (-1790 4210);
PAINT MONO (-1790 4210);
DISPLAY INVISIBLE (-1790 4210);
FORCEPROP 1 LASTPIN (-1800 4200) BN 45
J 2
(-1750 4210);
DISPLAY 0.617021 (-1750 4210);
PAINT PINK (-1750 4210);
FORCEPROP 2 LAST CDS_LIB mstr_standard
J 2
(-1750 4200);
DISPLAY 0.787234 (-1750 4200);
PAINT MONO (-1750 4200);
DISPLAY INVISIBLE (-1750 4200);
FORCEPROP 1 LAST BODY_TYPE PLUMBING
J 2
(-1750 4150);
DISPLAY 1.234043 (-1750 4150);
PAINT GREEN (-1750 4150);
DISPLAY INVISIBLE (-1750 4150);
FORCEPROP 1 LAST HDL_TAP TRUE
J 2
(-2075 4075);
DISPLAY 1.234043 (-2075 4075);
PAINT GREEN (-2075 4075);
DISPLAY INVISIBLE (-2075 4075);
FORCEPROP 1 LAST PATH I65
J 2
(-1750 4200);
DISPLAY 0.936170 (-1750 4200);
PAINT GREEN (-1750 4200);
DISPLAY INVISIBLE (-1750 4200);
FORCEADD SCONN288_H44441004..2
(-50 4350);
FORCEPROP 1 LAST LOCATION J4B1
J 0
(-450 5450);
DISPLAY 0.617021 (-450 5450);
PAINT AQUA (-450 5450);
FORCEPROP 1 LAST PART_NUMBER H44441-004
J 0
(-450 3250);
DISPLAY 0.617021 (-450 3250);
PAINT BLUE (-450 3250);
FORCEPROP 1 LAST MATERIAL SCONN
J 0
(-450 5400);
DISPLAY 0.617021 (-450 5400);
PAINT SKYBLUE (-450 5400);
FORCEPROP 2 LASTPIN (400 5200) $PN 51
J 0
(410 5210);
DISPLAY 0.617021 (410 5210);
PAINT ORANGE (410 5210);
FORCEPROP 2 LASTPIN (400 5150) $PN 52
J 0
(410 5160);
DISPLAY 0.617021 (410 5160);
PAINT ORANGE (410 5160);
FORCEPROP 2 LASTPIN (400 5100) $PN 132
J 0
(410 5110);
DISPLAY 0.617021 (410 5110);
PAINT ORANGE (410 5110);
FORCEPROP 2 LASTPIN (400 5050) $PN 133
J 0
(410 5060);
DISPLAY 0.617021 (410 5060);
PAINT ORANGE (410 5060);
FORCEPROP 2 LASTPIN (400 5000) $PN 121
J 0
(410 5010);
DISPLAY 0.617021 (410 5010);
PAINT ORANGE (410 5010);
FORCEPROP 2 LASTPIN (400 4950) $PN 122
J 0
(410 4960);
DISPLAY 0.617021 (410 4960);
PAINT ORANGE (410 4960);
FORCEPROP 2 LASTPIN (400 4900) $PN 110
J 0
(410 4910);
DISPLAY 0.617021 (410 4910);
PAINT ORANGE (410 4910);
FORCEPROP 2 LASTPIN (400 4850) $PN 111
J 0
(410 4860);
DISPLAY 0.617021 (410 4860);
PAINT ORANGE (410 4860);
FORCEPROP 2 LASTPIN (400 4800) $PN 99
J 0
(410 4810);
DISPLAY 0.617021 (410 4810);
PAINT ORANGE (410 4810);
FORCEPROP 2 LASTPIN (400 4750) $PN 100
J 0
(410 4760);
DISPLAY 0.617021 (410 4760);
PAINT ORANGE (410 4760);
FORCEPROP 2 LASTPIN (400 4700) $PN 40
J 0
(410 4710);
DISPLAY 0.617021 (410 4710);
PAINT ORANGE (410 4710);
FORCEPROP 2 LASTPIN (400 4650) $PN 41
J 0
(410 4660);
DISPLAY 0.617021 (410 4660);
PAINT ORANGE (410 4660);
FORCEPROP 2 LASTPIN (400 4600) $PN 29
J 0
(410 4610);
DISPLAY 0.617021 (410 4610);
PAINT ORANGE (410 4610);
FORCEPROP 2 LASTPIN (400 4550) $PN 30
J 0
(410 4560);
DISPLAY 0.617021 (410 4560);
PAINT ORANGE (410 4560);
FORCEPROP 2 LASTPIN (400 4500) $PN 18
J 0
(410 4510);
DISPLAY 0.617021 (410 4510);
PAINT ORANGE (410 4510);
FORCEPROP 2 LASTPIN (400 4450) $PN 19
J 0
(410 4460);
DISPLAY 0.617021 (410 4460);
PAINT ORANGE (410 4460);
FORCEPROP 2 LASTPIN (400 4400) $PN 7
J 0
(410 4410);
DISPLAY 0.617021 (410 4410);
PAINT ORANGE (410 4410);
FORCEPROP 2 LASTPIN (400 4350) $PN 8
J 0
(410 4360);
DISPLAY 0.617021 (410 4360);
PAINT ORANGE (410 4360);
FORCEPROP 2 LASTPIN (400 4300) $PN 197
J 0
(410 4310);
DISPLAY 0.617021 (410 4310);
PAINT ORANGE (410 4310);
FORCEPROP 2 LASTPIN (400 4250) $PN 196
J 0
(410 4260);
DISPLAY 0.617021 (410 4260);
PAINT ORANGE (410 4260);
FORCEPROP 2 LASTPIN (400 4200) $PN 278
J 0
(410 4210);
DISPLAY 0.617021 (410 4210);
PAINT ORANGE (410 4210);
FORCEPROP 2 LASTPIN (400 4150) $PN 277
J 0
(410 4160);
DISPLAY 0.617021 (410 4160);
PAINT ORANGE (410 4160);
FORCEPROP 2 LASTPIN (400 4100) $PN 267
J 0
(410 4110);
DISPLAY 0.617021 (410 4110);
PAINT ORANGE (410 4110);
FORCEPROP 2 LASTPIN (400 4050) $PN 266
J 0
(410 4060);
DISPLAY 0.617021 (410 4060);
PAINT ORANGE (410 4060);
FORCEPROP 2 LASTPIN (400 4000) $PN 256
J 0
(410 4010);
DISPLAY 0.617021 (410 4010);
PAINT ORANGE (410 4010);
FORCEPROP 2 LASTPIN (400 3950) $PN 255
J 0
(410 3960);
DISPLAY 0.617021 (410 3960);
PAINT ORANGE (410 3960);
FORCEPROP 2 LASTPIN (400 3900) $PN 245
J 0
(410 3910);
DISPLAY 0.617021 (410 3910);
PAINT ORANGE (410 3910);
FORCEPROP 2 LASTPIN (400 3850) $PN 244
J 0
(410 3860);
DISPLAY 0.617021 (410 3860);
PAINT ORANGE (410 3860);
FORCEPROP 2 LASTPIN (400 3800) $PN 186
J 0
(410 3810);
DISPLAY 0.617021 (410 3810);
PAINT ORANGE (410 3810);
FORCEPROP 2 LASTPIN (400 3750) $PN 185
J 0
(410 3760);
DISPLAY 0.617021 (410 3760);
PAINT ORANGE (410 3760);
FORCEPROP 2 LASTPIN (400 3700) $PN 175
J 0
(410 3710);
DISPLAY 0.617021 (410 3710);
PAINT ORANGE (410 3710);
FORCEPROP 2 LASTPIN (400 3650) $PN 174
J 0
(410 3660);
DISPLAY 0.617021 (410 3660);
PAINT ORANGE (410 3660);
FORCEPROP 2 LASTPIN (400 3600) $PN 164
J 0
(410 3610);
DISPLAY 0.617021 (410 3610);
PAINT ORANGE (410 3610);
FORCEPROP 2 LASTPIN (400 3550) $PN 163
J 0
(410 3560);
DISPLAY 0.617021 (410 3560);
PAINT ORANGE (410 3560);
FORCEPROP 2 LASTPIN (400 3500) $PN 153
J 0
(410 3510);
DISPLAY 0.617021 (410 3510);
PAINT ORANGE (410 3510);
FORCEPROP 2 LASTPIN (400 3450) $PN 152
J 0
(410 3460);
DISPLAY 0.617021 (410 3460);
PAINT ORANGE (410 3460);
FORCEPROP 1 LAST PACK_TYPE PIP
J 0
(-450 5500);
PAINT SKYBLUE (-450 5500);
DISPLAY INVISIBLE (-450 5500);
FORCEPROP 2 LAST BOM_COST MEM
J 0
(-50 4350);
PAINT ORANGE (-50 4350);
DISPLAY INVISIBLE (-50 4350);
FORCEPROP 2 LAST CDS_LIB mstr_sconn
J 0
(-50 4350);
PAINT ORANGE (-50 4350);
DISPLAY INVISIBLE (-50 4350);
FORCEPROP 2 LAST SEC_TYPE PIP
J 0
(-450 5500);
DISPLAY 1.021277 (-450 5500);
PAINT ORANGE (-450 5500);
DISPLAY INVISIBLE (-450 5500);
FORCEPROP 2 LAST SEC 2
J 0
(-450 5500);
DISPLAY 0.680851 (-450 5500);
PAINT MONO (-450 5500);
DISPLAY INVISIBLE (-450 5500);
FORCEPROP 2 LAST CDS_LOCATION J4B1
J 0
(-450 5450);
DISPLAY 0.617021 (-450 5450);
PAINT AQUA (-450 5450);
DISPLAY INVISIBLE (-450 5450);
FORCEPROP 1 LAST PATH I66
J 0
(-50 5400);
PAINT GREEN (-50 5400);
DISPLAY INVISIBLE (-50 5400);
FORCEPROP 2 LAST ROOM DDR4_CH_D
J 0
(-50 4350);
PAINT ORANGE (-50 4350);
DISPLAY INVISIBLE (-50 4350);
FORCEADD TAP..6
R 2
(-1750 4150);
FORCEPROP 3 LASTPIN (-1800 4150) SIG_NAME M_D_DQ<42>
J 0
(-1790 4160);
DISPLAY 0.659574 (-1790 4160);
PAINT MONO (-1790 4160);
DISPLAY INVISIBLE (-1790 4160);
FORCEPROP 1 LASTPIN (-1800 4150) BN 42
J 2
(-1750 4160);
DISPLAY 0.617021 (-1750 4160);
PAINT PINK (-1750 4160);
FORCEPROP 2 LAST CDS_LIB mstr_standard
J 2
(-1750 4150);
DISPLAY 0.787234 (-1750 4150);
PAINT MONO (-1750 4150);
DISPLAY INVISIBLE (-1750 4150);
FORCEPROP 1 LAST BODY_TYPE PLUMBING
J 2
(-1750 4100);
DISPLAY 1.234043 (-1750 4100);
PAINT GREEN (-1750 4100);
DISPLAY INVISIBLE (-1750 4100);
FORCEPROP 1 LAST HDL_TAP TRUE
J 2
(-2075 4025);
DISPLAY 1.234043 (-2075 4025);
PAINT GREEN (-2075 4025);
DISPLAY INVISIBLE (-2075 4025);
FORCEPROP 1 LAST PATH I67
J 2
(-1750 4150);
DISPLAY 0.936170 (-1750 4150);
PAINT GREEN (-1750 4150);
DISPLAY INVISIBLE (-1750 4150);
FORCEADD TAP..6
R 2
(-1750 4100);
FORCEPROP 3 LASTPIN (-1800 4100) SIG_NAME M_D_DQ<43>
J 0
(-1790 4110);
DISPLAY 0.659574 (-1790 4110);
PAINT MONO (-1790 4110);
DISPLAY INVISIBLE (-1790 4110);
FORCEPROP 1 LASTPIN (-1800 4100) BN 43
J 2
(-1750 4110);
DISPLAY 0.617021 (-1750 4110);
PAINT PINK (-1750 4110);
FORCEPROP 2 LAST CDS_LIB mstr_standard
J 2
(-1750 4100);
DISPLAY 0.787234 (-1750 4100);
PAINT MONO (-1750 4100);
DISPLAY INVISIBLE (-1750 4100);
FORCEPROP 1 LAST BODY_TYPE PLUMBING
J 2
(-1750 4050);
DISPLAY 1.234043 (-1750 4050);
PAINT GREEN (-1750 4050);
DISPLAY INVISIBLE (-1750 4050);
FORCEPROP 1 LAST HDL_TAP TRUE
J 2
(-2075 3975);
DISPLAY 1.234043 (-2075 3975);
PAINT GREEN (-2075 3975);
DISPLAY INVISIBLE (-2075 3975);
FORCEPROP 1 LAST PATH I68
J 2
(-1750 4100);
DISPLAY 0.936170 (-1750 4100);
PAINT GREEN (-1750 4100);
DISPLAY INVISIBLE (-1750 4100);
FORCEADD TAP..6
R 2
(-1750 4000);
FORCEPROP 3 LASTPIN (-1800 4000) SIG_NAME M_D_DQ<41>
J 0
(-1790 4010);
DISPLAY 0.659574 (-1790 4010);
PAINT MONO (-1790 4010);
DISPLAY INVISIBLE (-1790 4010);
FORCEPROP 1 LASTPIN (-1800 4000) BN 41
J 2
(-1750 4010);
DISPLAY 0.617021 (-1750 4010);
PAINT PINK (-1750 4010);
FORCEPROP 2 LAST CDS_LIB mstr_standard
J 2
(-1750 4000);
DISPLAY 0.787234 (-1750 4000);
PAINT MONO (-1750 4000);
DISPLAY INVISIBLE (-1750 4000);
FORCEPROP 1 LAST BODY_TYPE PLUMBING
J 2
(-1750 3950);
DISPLAY 1.234043 (-1750 3950);
PAINT GREEN (-1750 3950);
DISPLAY INVISIBLE (-1750 3950);
FORCEPROP 1 LAST HDL_TAP TRUE
J 2
(-2075 3875);
DISPLAY 1.234043 (-2075 3875);
PAINT GREEN (-2075 3875);
DISPLAY INVISIBLE (-2075 3875);
FORCEPROP 1 LAST PATH I69
J 2
(-1750 4000);
DISPLAY 0.936170 (-1750 4000);
PAINT GREEN (-1750 4000);
DISPLAY INVISIBLE (-1750 4000);
FORCEADD TAP..6
R 2
(900 4750);
FORCEPROP 3 LASTPIN (850 4750) SIG_NAME M_D_DQS_DN<13>
J 0
(860 4760);
DISPLAY 0.659574 (860 4760);
PAINT MONO (860 4760);
DISPLAY INVISIBLE (860 4760);
FORCEPROP 1 LASTPIN (850 4750) BN 13
J 2
(900 4760);
DISPLAY 0.617021 (900 4760);
PAINT PINK (900 4760);
FORCEPROP 2 LAST CDS_LIB mstr_standard
J 0
(900 4750);
DISPLAY 0.787234 (900 4750);
PAINT MONO (900 4750);
DISPLAY INVISIBLE (900 4750);
FORCEPROP 1 LAST BODY_TYPE PLUMBING
J 2
(900 4700);
DISPLAY 1.234043 (900 4700);
PAINT GREEN (900 4700);
DISPLAY INVISIBLE (900 4700);
FORCEPROP 1 LAST HDL_TAP TRUE
J 2
(575 4625);
DISPLAY 1.234043 (575 4625);
PAINT GREEN (575 4625);
DISPLAY INVISIBLE (575 4625);
FORCEPROP 1 LAST PATH I7
J 2
(900 4750);
DISPLAY 0.936170 (900 4750);
PAINT GREEN (900 4750);
DISPLAY INVISIBLE (900 4750);
FORCEADD TAP..6
R 2
(-1750 3950);
FORCEPROP 3 LASTPIN (-1800 3950) SIG_NAME M_D_DQ<38>
J 0
(-1790 3960);
DISPLAY 0.659574 (-1790 3960);
PAINT MONO (-1790 3960);
DISPLAY INVISIBLE (-1790 3960);
FORCEPROP 1 LASTPIN (-1800 3950) BN 38
J 2
(-1750 3960);
DISPLAY 0.617021 (-1750 3960);
PAINT PINK (-1750 3960);
FORCEPROP 2 LAST CDS_LIB mstr_standard
J 2
(-1750 3950);
DISPLAY 0.787234 (-1750 3950);
PAINT MONO (-1750 3950);
DISPLAY INVISIBLE (-1750 3950);
FORCEPROP 1 LAST BODY_TYPE PLUMBING
J 2
(-1750 3900);
DISPLAY 1.234043 (-1750 3900);
PAINT GREEN (-1750 3900);
DISPLAY INVISIBLE (-1750 3900);
FORCEPROP 1 LAST HDL_TAP TRUE
J 2
(-2075 3825);
DISPLAY 1.234043 (-2075 3825);
PAINT GREEN (-2075 3825);
DISPLAY INVISIBLE (-2075 3825);
FORCEPROP 1 LAST PATH I70
J 2
(-1750 3950);
DISPLAY 0.936170 (-1750 3950);
PAINT GREEN (-1750 3950);
DISPLAY INVISIBLE (-1750 3950);
FORCEADD TAP..6
R 2
(-1750 4050);
FORCEPROP 3 LASTPIN (-1800 4050) SIG_NAME M_D_DQ<40>
J 0
(-1790 4060);
DISPLAY 0.659574 (-1790 4060);
PAINT MONO (-1790 4060);
DISPLAY INVISIBLE (-1790 4060);
FORCEPROP 1 LASTPIN (-1800 4050) BN 40
J 2
(-1750 4060);
DISPLAY 0.617021 (-1750 4060);
PAINT PINK (-1750 4060);
FORCEPROP 2 LAST CDS_LIB mstr_standard
J 2
(-1750 4050);
DISPLAY 0.787234 (-1750 4050);
PAINT MONO (-1750 4050);
DISPLAY INVISIBLE (-1750 4050);
FORCEPROP 1 LAST BODY_TYPE PLUMBING
J 2
(-1750 4000);
DISPLAY 1.234043 (-1750 4000);
PAINT GREEN (-1750 4000);
DISPLAY INVISIBLE (-1750 4000);
FORCEPROP 1 LAST HDL_TAP TRUE
J 2
(-2075 3925);
DISPLAY 1.234043 (-2075 3925);
PAINT GREEN (-2075 3925);
DISPLAY INVISIBLE (-2075 3925);
FORCEPROP 1 LAST PATH I71
J 2
(-1750 4050);
DISPLAY 0.936170 (-1750 4050);
PAINT GREEN (-1750 4050);
DISPLAY INVISIBLE (-1750 4050);
FORCEADD TAP..6
R 2
(-1750 3900);
FORCEPROP 3 LASTPIN (-1800 3900) SIG_NAME M_D_DQ<39>
J 0
(-1790 3910);
DISPLAY 0.659574 (-1790 3910);
PAINT MONO (-1790 3910);
DISPLAY INVISIBLE (-1790 3910);
FORCEPROP 1 LASTPIN (-1800 3900) BN 39
J 2
(-1750 3910);
DISPLAY 0.617021 (-1750 3910);
PAINT PINK (-1750 3910);
FORCEPROP 2 LAST CDS_LIB mstr_standard
J 2
(-1750 3900);
DISPLAY 0.787234 (-1750 3900);
PAINT MONO (-1750 3900);
DISPLAY INVISIBLE (-1750 3900);
FORCEPROP 1 LAST BODY_TYPE PLUMBING
J 2
(-1750 3850);
DISPLAY 1.234043 (-1750 3850);
PAINT GREEN (-1750 3850);
DISPLAY INVISIBLE (-1750 3850);
FORCEPROP 1 LAST HDL_TAP TRUE
J 2
(-2075 3775);
DISPLAY 1.234043 (-2075 3775);
PAINT GREEN (-2075 3775);
DISPLAY INVISIBLE (-2075 3775);
FORCEPROP 1 LAST PATH I72
J 2
(-1750 3900);
DISPLAY 0.936170 (-1750 3900);
PAINT GREEN (-1750 3900);
DISPLAY INVISIBLE (-1750 3900);
FORCEADD TAP..6
R 2
(-1750 3850);
FORCEPROP 3 LASTPIN (-1800 3850) SIG_NAME M_D_DQ<36>
J 0
(-1790 3860);
DISPLAY 0.659574 (-1790 3860);
PAINT MONO (-1790 3860);
DISPLAY INVISIBLE (-1790 3860);
FORCEPROP 1 LASTPIN (-1800 3850) BN 36
J 2
(-1750 3860);
DISPLAY 0.617021 (-1750 3860);
PAINT PINK (-1750 3860);
FORCEPROP 2 LAST CDS_LIB mstr_standard
J 2
(-1750 3850);
DISPLAY 0.787234 (-1750 3850);
PAINT MONO (-1750 3850);
DISPLAY INVISIBLE (-1750 3850);
FORCEPROP 1 LAST BODY_TYPE PLUMBING
J 2
(-1750 3800);
DISPLAY 1.234043 (-1750 3800);
PAINT GREEN (-1750 3800);
DISPLAY INVISIBLE (-1750 3800);
FORCEPROP 1 LAST HDL_TAP TRUE
J 2
(-2075 3725);
DISPLAY 1.234043 (-2075 3725);
PAINT GREEN (-2075 3725);
DISPLAY INVISIBLE (-2075 3725);
FORCEPROP 1 LAST PATH I73
J 2
(-1750 3850);
DISPLAY 0.936170 (-1750 3850);
PAINT GREEN (-1750 3850);
DISPLAY INVISIBLE (-1750 3850);
FORCEADD TAP..6
R 2
(-1750 3800);
FORCEPROP 3 LASTPIN (-1800 3800) SIG_NAME M_D_DQ<37>
J 0
(-1790 3810);
DISPLAY 0.659574 (-1790 3810);
PAINT MONO (-1790 3810);
DISPLAY INVISIBLE (-1790 3810);
FORCEPROP 1 LASTPIN (-1800 3800) BN 37
J 2
(-1750 3810);
DISPLAY 0.617021 (-1750 3810);
PAINT PINK (-1750 3810);
FORCEPROP 2 LAST CDS_LIB mstr_standard
J 2
(-1750 3800);
DISPLAY 0.787234 (-1750 3800);
PAINT MONO (-1750 3800);
DISPLAY INVISIBLE (-1750 3800);
FORCEPROP 1 LAST BODY_TYPE PLUMBING
J 2
(-1750 3750);
DISPLAY 1.234043 (-1750 3750);
PAINT GREEN (-1750 3750);
DISPLAY INVISIBLE (-1750 3750);
FORCEPROP 1 LAST HDL_TAP TRUE
J 2
(-2075 3675);
DISPLAY 1.234043 (-2075 3675);
PAINT GREEN (-2075 3675);
DISPLAY INVISIBLE (-2075 3675);
FORCEPROP 1 LAST PATH I74
J 2
(-1750 3800);
DISPLAY 0.936170 (-1750 3800);
PAINT GREEN (-1750 3800);
DISPLAY INVISIBLE (-1750 3800);
FORCEADD TAP..6
R 2
(-1750 3700);
FORCEPROP 3 LASTPIN (-1800 3700) SIG_NAME M_D_DQ<35>
J 0
(-1790 3710);
DISPLAY 0.659574 (-1790 3710);
PAINT MONO (-1790 3710);
DISPLAY INVISIBLE (-1790 3710);
FORCEPROP 1 LASTPIN (-1800 3700) BN 35
J 2
(-1750 3710);
DISPLAY 0.617021 (-1750 3710);
PAINT PINK (-1750 3710);
FORCEPROP 2 LAST CDS_LIB mstr_standard
J 2
(-1750 3700);
DISPLAY 0.787234 (-1750 3700);
PAINT MONO (-1750 3700);
DISPLAY INVISIBLE (-1750 3700);
FORCEPROP 1 LAST BODY_TYPE PLUMBING
J 2
(-1750 3650);
DISPLAY 1.234043 (-1750 3650);
PAINT GREEN (-1750 3650);
DISPLAY INVISIBLE (-1750 3650);
FORCEPROP 1 LAST HDL_TAP TRUE
J 2
(-2075 3575);
DISPLAY 1.234043 (-2075 3575);
PAINT GREEN (-2075 3575);
DISPLAY INVISIBLE (-2075 3575);
FORCEPROP 1 LAST PATH I75
J 2
(-1750 3700);
DISPLAY 0.936170 (-1750 3700);
PAINT GREEN (-1750 3700);
DISPLAY INVISIBLE (-1750 3700);
FORCEADD TAP..6
R 2
(-1750 3750);
FORCEPROP 3 LASTPIN (-1800 3750) SIG_NAME M_D_DQ<34>
J 0
(-1790 3760);
DISPLAY 0.659574 (-1790 3760);
PAINT MONO (-1790 3760);
DISPLAY INVISIBLE (-1790 3760);
FORCEPROP 1 LASTPIN (-1800 3750) BN 34
J 2
(-1750 3760);
DISPLAY 0.617021 (-1750 3760);
PAINT PINK (-1750 3760);
FORCEPROP 2 LAST CDS_LIB mstr_standard
J 2
(-1750 3750);
DISPLAY 0.787234 (-1750 3750);
PAINT MONO (-1750 3750);
DISPLAY INVISIBLE (-1750 3750);
FORCEPROP 1 LAST BODY_TYPE PLUMBING
J 2
(-1750 3700);
DISPLAY 1.234043 (-1750 3700);
PAINT GREEN (-1750 3700);
DISPLAY INVISIBLE (-1750 3700);
FORCEPROP 1 LAST HDL_TAP TRUE
J 2
(-2075 3625);
DISPLAY 1.234043 (-2075 3625);
PAINT GREEN (-2075 3625);
DISPLAY INVISIBLE (-2075 3625);
FORCEPROP 1 LAST PATH I76
J 2
(-1750 3750);
DISPLAY 0.936170 (-1750 3750);
PAINT GREEN (-1750 3750);
DISPLAY INVISIBLE (-1750 3750);
FORCEADD TAP..6
R 2
(-1750 3650);
FORCEPROP 3 LASTPIN (-1800 3650) SIG_NAME M_D_DQ<32>
J 0
(-1790 3660);
DISPLAY 0.659574 (-1790 3660);
PAINT MONO (-1790 3660);
DISPLAY INVISIBLE (-1790 3660);
FORCEPROP 1 LASTPIN (-1800 3650) BN 32
J 2
(-1750 3660);
DISPLAY 0.617021 (-1750 3660);
PAINT PINK (-1750 3660);
FORCEPROP 2 LAST CDS_LIB mstr_standard
J 2
(-1750 3650);
DISPLAY 0.787234 (-1750 3650);
PAINT MONO (-1750 3650);
DISPLAY INVISIBLE (-1750 3650);
FORCEPROP 1 LAST BODY_TYPE PLUMBING
J 2
(-1750 3600);
DISPLAY 1.234043 (-1750 3600);
PAINT GREEN (-1750 3600);
DISPLAY INVISIBLE (-1750 3600);
FORCEPROP 1 LAST HDL_TAP TRUE
J 2
(-2075 3525);
DISPLAY 1.234043 (-2075 3525);
PAINT GREEN (-2075 3525);
DISPLAY INVISIBLE (-2075 3525);
FORCEPROP 1 LAST PATH I77
J 2
(-1750 3650);
DISPLAY 0.936170 (-1750 3650);
PAINT GREEN (-1750 3650);
DISPLAY INVISIBLE (-1750 3650);
FORCEADD TAP..6
R 2
(-1750 3600);
FORCEPROP 3 LASTPIN (-1800 3600) SIG_NAME M_D_DQ<33>
J 0
(-1790 3610);
DISPLAY 0.659574 (-1790 3610);
PAINT MONO (-1790 3610);
DISPLAY INVISIBLE (-1790 3610);
FORCEPROP 1 LASTPIN (-1800 3600) BN 33
J 2
(-1750 3610);
DISPLAY 0.617021 (-1750 3610);
PAINT PINK (-1750 3610);
FORCEPROP 2 LAST CDS_LIB mstr_standard
J 2
(-1750 3600);
DISPLAY 0.787234 (-1750 3600);
PAINT MONO (-1750 3600);
DISPLAY INVISIBLE (-1750 3600);
FORCEPROP 1 LAST BODY_TYPE PLUMBING
J 2
(-1750 3550);
DISPLAY 1.234043 (-1750 3550);
PAINT GREEN (-1750 3550);
DISPLAY INVISIBLE (-1750 3550);
FORCEPROP 1 LAST HDL_TAP TRUE
J 2
(-2075 3475);
DISPLAY 1.234043 (-2075 3475);
PAINT GREEN (-2075 3475);
DISPLAY INVISIBLE (-2075 3475);
FORCEPROP 1 LAST PATH I78
J 2
(-1750 3600);
DISPLAY 0.936170 (-1750 3600);
PAINT GREEN (-1750 3600);
DISPLAY INVISIBLE (-1750 3600);
FORCEADD TAP..6
R 2
(-1750 3450);
FORCEPROP 3 LASTPIN (-1800 3450) SIG_NAME M_D_DQ<28>
J 0
(-1790 3460);
DISPLAY 0.659574 (-1790 3460);
PAINT MONO (-1790 3460);
DISPLAY INVISIBLE (-1790 3460);
FORCEPROP 1 LASTPIN (-1800 3450) BN 28
J 2
(-1750 3460);
DISPLAY 0.617021 (-1750 3460);
PAINT PINK (-1750 3460);
FORCEPROP 2 LAST CDS_LIB mstr_standard
J 2
(-1750 3450);
DISPLAY 0.787234 (-1750 3450);
PAINT MONO (-1750 3450);
DISPLAY INVISIBLE (-1750 3450);
FORCEPROP 1 LAST BODY_TYPE PLUMBING
J 2
(-1750 3400);
DISPLAY 1.234043 (-1750 3400);
PAINT GREEN (-1750 3400);
DISPLAY INVISIBLE (-1750 3400);
FORCEPROP 1 LAST HDL_TAP TRUE
J 2
(-2075 3325);
DISPLAY 1.234043 (-2075 3325);
PAINT GREEN (-2075 3325);
DISPLAY INVISIBLE (-2075 3325);
FORCEPROP 1 LAST PATH I79
J 2
(-1750 3450);
DISPLAY 0.936170 (-1750 3450);
PAINT GREEN (-1750 3450);
DISPLAY INVISIBLE (-1750 3450);
FORCEADD TAP..6
R 2
(900 4850);
FORCEPROP 3 LASTPIN (850 4850) SIG_NAME M_D_DQS_DN<14>
J 0
(860 4860);
DISPLAY 0.659574 (860 4860);
PAINT MONO (860 4860);
DISPLAY INVISIBLE (860 4860);
FORCEPROP 1 LASTPIN (850 4850) BN 14
J 2
(900 4860);
DISPLAY 0.617021 (900 4860);
PAINT PINK (900 4860);
FORCEPROP 2 LAST CDS_LIB mstr_standard
J 0
(900 4850);
DISPLAY 0.787234 (900 4850);
PAINT MONO (900 4850);
DISPLAY INVISIBLE (900 4850);
FORCEPROP 1 LAST BODY_TYPE PLUMBING
J 2
(900 4800);
DISPLAY 1.234043 (900 4800);
PAINT GREEN (900 4800);
DISPLAY INVISIBLE (900 4800);
FORCEPROP 1 LAST HDL_TAP TRUE
J 2
(575 4725);
DISPLAY 1.234043 (575 4725);
PAINT GREEN (575 4725);
DISPLAY INVISIBLE (575 4725);
FORCEPROP 1 LAST PATH I8
J 2
(900 4850);
DISPLAY 0.936170 (900 4850);
PAINT GREEN (900 4850);
DISPLAY INVISIBLE (900 4850);
FORCEADD TAP..6
R 2
(-1750 3550);
FORCEPROP 3 LASTPIN (-1800 3550) SIG_NAME M_D_DQ<30>
J 0
(-1790 3560);
DISPLAY 0.659574 (-1790 3560);
PAINT MONO (-1790 3560);
DISPLAY INVISIBLE (-1790 3560);
FORCEPROP 1 LASTPIN (-1800 3550) BN 30
J 2
(-1750 3560);
DISPLAY 0.617021 (-1750 3560);
PAINT PINK (-1750 3560);
FORCEPROP 2 LAST CDS_LIB mstr_standard
J 2
(-1750 3550);
DISPLAY 0.787234 (-1750 3550);
PAINT MONO (-1750 3550);
DISPLAY INVISIBLE (-1750 3550);
FORCEPROP 1 LAST BODY_TYPE PLUMBING
J 2
(-1750 3500);
DISPLAY 1.234043 (-1750 3500);
PAINT GREEN (-1750 3500);
DISPLAY INVISIBLE (-1750 3500);
FORCEPROP 1 LAST HDL_TAP TRUE
J 2
(-2075 3425);
DISPLAY 1.234043 (-2075 3425);
PAINT GREEN (-2075 3425);
DISPLAY INVISIBLE (-2075 3425);
FORCEPROP 1 LAST PATH I80
J 2
(-1750 3550);
DISPLAY 0.936170 (-1750 3550);
PAINT GREEN (-1750 3550);
DISPLAY INVISIBLE (-1750 3550);
FORCEADD TAP..6
R 2
(-1750 3500);
FORCEPROP 3 LASTPIN (-1800 3500) SIG_NAME M_D_DQ<31>
J 0
(-1790 3510);
DISPLAY 0.659574 (-1790 3510);
PAINT MONO (-1790 3510);
DISPLAY INVISIBLE (-1790 3510);
FORCEPROP 1 LASTPIN (-1800 3500) BN 31
J 2
(-1750 3510);
DISPLAY 0.617021 (-1750 3510);
PAINT PINK (-1750 3510);
FORCEPROP 2 LAST CDS_LIB mstr_standard
J 2
(-1750 3500);
DISPLAY 0.787234 (-1750 3500);
PAINT MONO (-1750 3500);
DISPLAY INVISIBLE (-1750 3500);
FORCEPROP 1 LAST BODY_TYPE PLUMBING
J 2
(-1750 3450);
DISPLAY 1.234043 (-1750 3450);
PAINT GREEN (-1750 3450);
DISPLAY INVISIBLE (-1750 3450);
FORCEPROP 1 LAST HDL_TAP TRUE
J 2
(-2075 3375);
DISPLAY 1.234043 (-2075 3375);
PAINT GREEN (-2075 3375);
DISPLAY INVISIBLE (-2075 3375);
FORCEPROP 1 LAST PATH I81
J 2
(-1750 3500);
DISPLAY 0.936170 (-1750 3500);
PAINT GREEN (-1750 3500);
DISPLAY INVISIBLE (-1750 3500);
FORCEADD TAP..6
R 2
(-1750 3350);
FORCEPROP 3 LASTPIN (-1800 3350) SIG_NAME M_D_DQ<26>
J 0
(-1790 3360);
DISPLAY 0.659574 (-1790 3360);
PAINT MONO (-1790 3360);
DISPLAY INVISIBLE (-1790 3360);
FORCEPROP 1 LASTPIN (-1800 3350) BN 26
J 2
(-1750 3360);
DISPLAY 0.617021 (-1750 3360);
PAINT PINK (-1750 3360);
FORCEPROP 2 LAST CDS_LIB mstr_standard
J 2
(-1750 3350);
DISPLAY 0.787234 (-1750 3350);
PAINT MONO (-1750 3350);
DISPLAY INVISIBLE (-1750 3350);
FORCEPROP 1 LAST BODY_TYPE PLUMBING
J 2
(-1750 3300);
DISPLAY 1.234043 (-1750 3300);
PAINT GREEN (-1750 3300);
DISPLAY INVISIBLE (-1750 3300);
FORCEPROP 1 LAST HDL_TAP TRUE
J 2
(-2075 3225);
DISPLAY 1.234043 (-2075 3225);
PAINT GREEN (-2075 3225);
DISPLAY INVISIBLE (-2075 3225);
FORCEPROP 1 LAST PATH I82
J 2
(-1750 3350);
DISPLAY 0.936170 (-1750 3350);
PAINT GREEN (-1750 3350);
DISPLAY INVISIBLE (-1750 3350);
FORCEADD TAP..6
R 2
(-1750 3400);
FORCEPROP 3 LASTPIN (-1800 3400) SIG_NAME M_D_DQ<29>
J 0
(-1790 3410);
DISPLAY 0.659574 (-1790 3410);
PAINT MONO (-1790 3410);
DISPLAY INVISIBLE (-1790 3410);
FORCEPROP 1 LASTPIN (-1800 3400) BN 29
J 2
(-1750 3410);
DISPLAY 0.617021 (-1750 3410);
PAINT PINK (-1750 3410);
FORCEPROP 2 LAST CDS_LIB mstr_standard
J 2
(-1750 3400);
DISPLAY 0.787234 (-1750 3400);
PAINT MONO (-1750 3400);
DISPLAY INVISIBLE (-1750 3400);
FORCEPROP 1 LAST BODY_TYPE PLUMBING
J 2
(-1750 3350);
DISPLAY 1.234043 (-1750 3350);
PAINT GREEN (-1750 3350);
DISPLAY INVISIBLE (-1750 3350);
FORCEPROP 1 LAST HDL_TAP TRUE
J 2
(-2075 3275);
DISPLAY 1.234043 (-2075 3275);
PAINT GREEN (-2075 3275);
DISPLAY INVISIBLE (-2075 3275);
FORCEPROP 1 LAST PATH I83
J 2
(-1750 3400);
DISPLAY 0.936170 (-1750 3400);
PAINT GREEN (-1750 3400);
DISPLAY INVISIBLE (-1750 3400);
FORCEADD TAP..6
R 2
(-1750 3300);
FORCEPROP 3 LASTPIN (-1800 3300) SIG_NAME M_D_DQ<27>
J 0
(-1790 3310);
DISPLAY 0.659574 (-1790 3310);
PAINT MONO (-1790 3310);
DISPLAY INVISIBLE (-1790 3310);
FORCEPROP 1 LASTPIN (-1800 3300) BN 27
J 2
(-1750 3310);
DISPLAY 0.617021 (-1750 3310);
PAINT PINK (-1750 3310);
FORCEPROP 2 LAST CDS_LIB mstr_standard
J 2
(-1750 3300);
DISPLAY 0.787234 (-1750 3300);
PAINT MONO (-1750 3300);
DISPLAY INVISIBLE (-1750 3300);
FORCEPROP 1 LAST BODY_TYPE PLUMBING
J 2
(-1750 3250);
DISPLAY 1.234043 (-1750 3250);
PAINT GREEN (-1750 3250);
DISPLAY INVISIBLE (-1750 3250);
FORCEPROP 1 LAST HDL_TAP TRUE
J 2
(-2075 3175);
DISPLAY 1.234043 (-2075 3175);
PAINT GREEN (-2075 3175);
DISPLAY INVISIBLE (-2075 3175);
FORCEPROP 1 LAST PATH I84
J 2
(-1750 3300);
DISPLAY 0.936170 (-1750 3300);
PAINT GREEN (-1750 3300);
DISPLAY INVISIBLE (-1750 3300);
FORCEADD TAP..6
R 2
(-1750 3200);
FORCEPROP 3 LASTPIN (-1800 3200) SIG_NAME M_D_DQ<25>
J 0
(-1790 3210);
DISPLAY 0.659574 (-1790 3210);
PAINT MONO (-1790 3210);
DISPLAY INVISIBLE (-1790 3210);
FORCEPROP 1 LASTPIN (-1800 3200) BN 25
J 2
(-1750 3210);
DISPLAY 0.617021 (-1750 3210);
PAINT PINK (-1750 3210);
FORCEPROP 2 LAST CDS_LIB mstr_standard
J 2
(-1750 3200);
DISPLAY 0.787234 (-1750 3200);
PAINT MONO (-1750 3200);
DISPLAY INVISIBLE (-1750 3200);
FORCEPROP 1 LAST BODY_TYPE PLUMBING
J 2
(-1750 3150);
DISPLAY 1.234043 (-1750 3150);
PAINT GREEN (-1750 3150);
DISPLAY INVISIBLE (-1750 3150);
FORCEPROP 1 LAST HDL_TAP TRUE
J 2
(-2075 3075);
DISPLAY 1.234043 (-2075 3075);
PAINT GREEN (-2075 3075);
DISPLAY INVISIBLE (-2075 3075);
FORCEPROP 1 LAST PATH I85
J 2
(-1750 3200);
DISPLAY 0.936170 (-1750 3200);
PAINT GREEN (-1750 3200);
DISPLAY INVISIBLE (-1750 3200);
FORCEADD TAP..6
R 2
(-1750 3250);
FORCEPROP 3 LASTPIN (-1800 3250) SIG_NAME M_D_DQ<24>
J 0
(-1790 3260);
DISPLAY 0.659574 (-1790 3260);
PAINT MONO (-1790 3260);
DISPLAY INVISIBLE (-1790 3260);
FORCEPROP 1 LASTPIN (-1800 3250) BN 24
J 2
(-1750 3260);
DISPLAY 0.617021 (-1750 3260);
PAINT PINK (-1750 3260);
FORCEPROP 2 LAST CDS_LIB mstr_standard
J 2
(-1750 3250);
DISPLAY 0.787234 (-1750 3250);
PAINT MONO (-1750 3250);
DISPLAY INVISIBLE (-1750 3250);
FORCEPROP 1 LAST BODY_TYPE PLUMBING
J 2
(-1750 3200);
DISPLAY 1.234043 (-1750 3200);
PAINT GREEN (-1750 3200);
DISPLAY INVISIBLE (-1750 3200);
FORCEPROP 1 LAST HDL_TAP TRUE
J 2
(-2075 3125);
DISPLAY 1.234043 (-2075 3125);
PAINT GREEN (-2075 3125);
DISPLAY INVISIBLE (-2075 3125);
FORCEPROP 1 LAST PATH I86
J 2
(-1750 3250);
DISPLAY 0.936170 (-1750 3250);
PAINT GREEN (-1750 3250);
DISPLAY INVISIBLE (-1750 3250);
FORCEADD TAP..6
R 2
(-1750 3100);
FORCEPROP 3 LASTPIN (-1800 3100) SIG_NAME M_D_DQ<23>
J 0
(-1790 3110);
DISPLAY 0.659574 (-1790 3110);
PAINT MONO (-1790 3110);
DISPLAY INVISIBLE (-1790 3110);
FORCEPROP 1 LASTPIN (-1800 3100) BN 23
J 2
(-1750 3110);
DISPLAY 0.617021 (-1750 3110);
PAINT PINK (-1750 3110);
FORCEPROP 2 LAST CDS_LIB mstr_standard
J 2
(-1750 3100);
DISPLAY 0.787234 (-1750 3100);
PAINT MONO (-1750 3100);
DISPLAY INVISIBLE (-1750 3100);
FORCEPROP 1 LAST BODY_TYPE PLUMBING
J 2
(-1750 3050);
DISPLAY 1.234043 (-1750 3050);
PAINT GREEN (-1750 3050);
DISPLAY INVISIBLE (-1750 3050);
FORCEPROP 1 LAST HDL_TAP TRUE
J 2
(-2075 2975);
DISPLAY 1.234043 (-2075 2975);
PAINT GREEN (-2075 2975);
DISPLAY INVISIBLE (-2075 2975);
FORCEPROP 1 LAST PATH I87
J 2
(-1750 3100);
DISPLAY 0.936170 (-1750 3100);
PAINT GREEN (-1750 3100);
DISPLAY INVISIBLE (-1750 3100);
FORCEADD TAP..6
R 2
(-1750 3150);
FORCEPROP 3 LASTPIN (-1800 3150) SIG_NAME M_D_DQ<22>
J 0
(-1790 3160);
DISPLAY 0.659574 (-1790 3160);
PAINT MONO (-1790 3160);
DISPLAY INVISIBLE (-1790 3160);
FORCEPROP 1 LASTPIN (-1800 3150) BN 22
J 2
(-1750 3160);
DISPLAY 0.617021 (-1750 3160);
PAINT PINK (-1750 3160);
FORCEPROP 2 LAST CDS_LIB mstr_standard
J 2
(-1750 3150);
DISPLAY 0.787234 (-1750 3150);
PAINT MONO (-1750 3150);
DISPLAY INVISIBLE (-1750 3150);
FORCEPROP 1 LAST BODY_TYPE PLUMBING
J 2
(-1750 3100);
DISPLAY 1.234043 (-1750 3100);
PAINT GREEN (-1750 3100);
DISPLAY INVISIBLE (-1750 3100);
FORCEPROP 1 LAST HDL_TAP TRUE
J 2
(-2075 3025);
DISPLAY 1.234043 (-2075 3025);
PAINT GREEN (-2075 3025);
DISPLAY INVISIBLE (-2075 3025);
FORCEPROP 1 LAST PATH I88
J 2
(-1750 3150);
DISPLAY 0.936170 (-1750 3150);
PAINT GREEN (-1750 3150);
DISPLAY INVISIBLE (-1750 3150);
FORCEADD TAP..6
R 2
(-1750 3050);
FORCEPROP 3 LASTPIN (-1800 3050) SIG_NAME M_D_DQ<20>
J 0
(-1790 3060);
DISPLAY 0.659574 (-1790 3060);
PAINT MONO (-1790 3060);
DISPLAY INVISIBLE (-1790 3060);
FORCEPROP 1 LASTPIN (-1800 3050) BN 20
J 2
(-1750 3060);
DISPLAY 0.617021 (-1750 3060);
PAINT PINK (-1750 3060);
FORCEPROP 2 LAST CDS_LIB mstr_standard
J 2
(-1750 3050);
DISPLAY 0.787234 (-1750 3050);
PAINT MONO (-1750 3050);
DISPLAY INVISIBLE (-1750 3050);
FORCEPROP 1 LAST BODY_TYPE PLUMBING
J 2
(-1750 3000);
DISPLAY 1.234043 (-1750 3000);
PAINT GREEN (-1750 3000);
DISPLAY INVISIBLE (-1750 3000);
FORCEPROP 1 LAST HDL_TAP TRUE
J 2
(-2075 2925);
DISPLAY 1.234043 (-2075 2925);
PAINT GREEN (-2075 2925);
DISPLAY INVISIBLE (-2075 2925);
FORCEPROP 1 LAST PATH I89
J 2
(-1750 3050);
DISPLAY 0.936170 (-1750 3050);
PAINT GREEN (-1750 3050);
DISPLAY INVISIBLE (-1750 3050);
FORCEADD TAP..6
R 2
(900 4650);
FORCEPROP 3 LASTPIN (850 4650) SIG_NAME M_D_DQS_DN<12>
J 0
(860 4660);
DISPLAY 0.659574 (860 4660);
PAINT MONO (860 4660);
DISPLAY INVISIBLE (860 4660);
FORCEPROP 1 LASTPIN (850 4650) BN 12
J 2
(900 4660);
DISPLAY 0.617021 (900 4660);
PAINT PINK (900 4660);
FORCEPROP 2 LAST CDS_LIB mstr_standard
J 0
(900 4650);
DISPLAY 0.787234 (900 4650);
PAINT MONO (900 4650);
DISPLAY INVISIBLE (900 4650);
FORCEPROP 1 LAST BODY_TYPE PLUMBING
J 2
(900 4600);
DISPLAY 1.234043 (900 4600);
PAINT GREEN (900 4600);
DISPLAY INVISIBLE (900 4600);
FORCEPROP 1 LAST HDL_TAP TRUE
J 2
(575 4525);
DISPLAY 1.234043 (575 4525);
PAINT GREEN (575 4525);
DISPLAY INVISIBLE (575 4525);
FORCEPROP 1 LAST PATH I9
J 2
(900 4650);
DISPLAY 0.936170 (900 4650);
PAINT GREEN (900 4650);
DISPLAY INVISIBLE (900 4650);
FORCEADD TAP..6
R 2
(-1750 3000);
FORCEPROP 3 LASTPIN (-1800 3000) SIG_NAME M_D_DQ<21>
J 0
(-1790 3010);
DISPLAY 0.659574 (-1790 3010);
PAINT MONO (-1790 3010);
DISPLAY INVISIBLE (-1790 3010);
FORCEPROP 1 LASTPIN (-1800 3000) BN 21
J 2
(-1750 3010);
DISPLAY 0.617021 (-1750 3010);
PAINT PINK (-1750 3010);
FORCEPROP 2 LAST CDS_LIB mstr_standard
J 2
(-1750 3000);
DISPLAY 0.787234 (-1750 3000);
PAINT MONO (-1750 3000);
DISPLAY INVISIBLE (-1750 3000);
FORCEPROP 1 LAST BODY_TYPE PLUMBING
J 2
(-1750 2950);
DISPLAY 1.234043 (-1750 2950);
PAINT GREEN (-1750 2950);
DISPLAY INVISIBLE (-1750 2950);
FORCEPROP 1 LAST HDL_TAP TRUE
J 2
(-2075 2875);
DISPLAY 1.234043 (-2075 2875);
PAINT GREEN (-2075 2875);
DISPLAY INVISIBLE (-2075 2875);
FORCEPROP 1 LAST PATH I90
J 2
(-1750 3000);
DISPLAY 0.936170 (-1750 3000);
PAINT GREEN (-1750 3000);
DISPLAY INVISIBLE (-1750 3000);
FORCEADD TAP..6
R 2
(-1750 2950);
FORCEPROP 3 LASTPIN (-1800 2950) SIG_NAME M_D_DQ<18>
J 0
(-1790 2960);
DISPLAY 0.659574 (-1790 2960);
PAINT MONO (-1790 2960);
DISPLAY INVISIBLE (-1790 2960);
FORCEPROP 1 LASTPIN (-1800 2950) BN 18
J 2
(-1750 2960);
DISPLAY 0.617021 (-1750 2960);
PAINT PINK (-1750 2960);
FORCEPROP 2 LAST CDS_LIB mstr_standard
J 2
(-1750 2950);
DISPLAY 0.787234 (-1750 2950);
PAINT MONO (-1750 2950);
DISPLAY INVISIBLE (-1750 2950);
FORCEPROP 1 LAST BODY_TYPE PLUMBING
J 2
(-1750 2900);
DISPLAY 1.234043 (-1750 2900);
PAINT GREEN (-1750 2900);
DISPLAY INVISIBLE (-1750 2900);
FORCEPROP 1 LAST HDL_TAP TRUE
J 2
(-2075 2825);
DISPLAY 1.234043 (-2075 2825);
PAINT GREEN (-2075 2825);
DISPLAY INVISIBLE (-2075 2825);
FORCEPROP 1 LAST PATH I91
J 2
(-1750 2950);
DISPLAY 0.936170 (-1750 2950);
PAINT GREEN (-1750 2950);
DISPLAY INVISIBLE (-1750 2950);
FORCEADD TAP..6
R 2
(-1750 2900);
FORCEPROP 3 LASTPIN (-1800 2900) SIG_NAME M_D_DQ<19>
J 0
(-1790 2910);
DISPLAY 0.659574 (-1790 2910);
PAINT MONO (-1790 2910);
DISPLAY INVISIBLE (-1790 2910);
FORCEPROP 1 LASTPIN (-1800 2900) BN 19
J 2
(-1750 2910);
DISPLAY 0.617021 (-1750 2910);
PAINT PINK (-1750 2910);
FORCEPROP 2 LAST CDS_LIB mstr_standard
J 2
(-1750 2900);
DISPLAY 0.787234 (-1750 2900);
PAINT MONO (-1750 2900);
DISPLAY INVISIBLE (-1750 2900);
FORCEPROP 1 LAST BODY_TYPE PLUMBING
J 2
(-1750 2850);
DISPLAY 1.234043 (-1750 2850);
PAINT GREEN (-1750 2850);
DISPLAY INVISIBLE (-1750 2850);
FORCEPROP 1 LAST HDL_TAP TRUE
J 2
(-2075 2775);
DISPLAY 1.234043 (-2075 2775);
PAINT GREEN (-2075 2775);
DISPLAY INVISIBLE (-2075 2775);
FORCEPROP 1 LAST PATH I92
J 2
(-1750 2900);
DISPLAY 0.936170 (-1750 2900);
PAINT GREEN (-1750 2900);
DISPLAY INVISIBLE (-1750 2900);
FORCEADD TAP..6
R 2
(-1750 2800);
FORCEPROP 3 LASTPIN (-1800 2800) SIG_NAME M_D_DQ<17>
J 0
(-1790 2810);
DISPLAY 0.659574 (-1790 2810);
PAINT MONO (-1790 2810);
DISPLAY INVISIBLE (-1790 2810);
FORCEPROP 1 LASTPIN (-1800 2800) BN 17
J 2
(-1750 2810);
DISPLAY 0.617021 (-1750 2810);
PAINT PINK (-1750 2810);
FORCEPROP 2 LAST CDS_LIB mstr_standard
J 2
(-1750 2800);
DISPLAY 0.787234 (-1750 2800);
PAINT MONO (-1750 2800);
DISPLAY INVISIBLE (-1750 2800);
FORCEPROP 1 LAST BODY_TYPE PLUMBING
J 2
(-1750 2750);
DISPLAY 1.234043 (-1750 2750);
PAINT GREEN (-1750 2750);
DISPLAY INVISIBLE (-1750 2750);
FORCEPROP 1 LAST HDL_TAP TRUE
J 2
(-2075 2675);
DISPLAY 1.234043 (-2075 2675);
PAINT GREEN (-2075 2675);
DISPLAY INVISIBLE (-2075 2675);
FORCEPROP 1 LAST PATH I93
J 2
(-1750 2800);
DISPLAY 0.936170 (-1750 2800);
PAINT GREEN (-1750 2800);
DISPLAY INVISIBLE (-1750 2800);
FORCEADD TAP..6
R 2
(-1750 2850);
FORCEPROP 3 LASTPIN (-1800 2850) SIG_NAME M_D_DQ<16>
J 0
(-1790 2860);
DISPLAY 0.659574 (-1790 2860);
PAINT MONO (-1790 2860);
DISPLAY INVISIBLE (-1790 2860);
FORCEPROP 1 LASTPIN (-1800 2850) BN 16
J 2
(-1750 2860);
DISPLAY 0.617021 (-1750 2860);
PAINT PINK (-1750 2860);
FORCEPROP 2 LAST CDS_LIB mstr_standard
J 2
(-1750 2850);
DISPLAY 0.787234 (-1750 2850);
PAINT MONO (-1750 2850);
DISPLAY INVISIBLE (-1750 2850);
FORCEPROP 1 LAST BODY_TYPE PLUMBING
J 2
(-1750 2800);
DISPLAY 1.234043 (-1750 2800);
PAINT GREEN (-1750 2800);
DISPLAY INVISIBLE (-1750 2800);
FORCEPROP 1 LAST HDL_TAP TRUE
J 2
(-2075 2725);
DISPLAY 1.234043 (-2075 2725);
PAINT GREEN (-2075 2725);
DISPLAY INVISIBLE (-2075 2725);
FORCEPROP 1 LAST PATH I94
J 2
(-1750 2850);
DISPLAY 0.936170 (-1750 2850);
PAINT GREEN (-1750 2850);
DISPLAY INVISIBLE (-1750 2850);
FORCEADD TAP..6
R 2
(-1750 2750);
FORCEPROP 3 LASTPIN (-1800 2750) SIG_NAME M_D_DQ<14>
J 0
(-1790 2760);
DISPLAY 0.659574 (-1790 2760);
PAINT MONO (-1790 2760);
DISPLAY INVISIBLE (-1790 2760);
FORCEPROP 1 LASTPIN (-1800 2750) BN 14
J 2
(-1750 2760);
DISPLAY 0.617021 (-1750 2760);
PAINT PINK (-1750 2760);
FORCEPROP 2 LAST CDS_LIB mstr_standard
J 2
(-1750 2750);
DISPLAY 0.787234 (-1750 2750);
PAINT MONO (-1750 2750);
DISPLAY INVISIBLE (-1750 2750);
FORCEPROP 1 LAST BODY_TYPE PLUMBING
J 2
(-1750 2700);
DISPLAY 1.234043 (-1750 2700);
PAINT GREEN (-1750 2700);
DISPLAY INVISIBLE (-1750 2700);
FORCEPROP 1 LAST HDL_TAP TRUE
J 2
(-2075 2625);
DISPLAY 1.234043 (-2075 2625);
PAINT GREEN (-2075 2625);
DISPLAY INVISIBLE (-2075 2625);
FORCEPROP 1 LAST PATH I95
J 2
(-1750 2750);
DISPLAY 0.936170 (-1750 2750);
PAINT GREEN (-1750 2750);
DISPLAY INVISIBLE (-1750 2750);
FORCEADD TAP..6
R 2
(-1750 2700);
FORCEPROP 3 LASTPIN (-1800 2700) SIG_NAME M_D_DQ<15>
J 0
(-1790 2710);
DISPLAY 0.659574 (-1790 2710);
PAINT MONO (-1790 2710);
DISPLAY INVISIBLE (-1790 2710);
FORCEPROP 1 LASTPIN (-1800 2700) BN 15
J 2
(-1750 2710);
DISPLAY 0.617021 (-1750 2710);
PAINT PINK (-1750 2710);
FORCEPROP 2 LAST CDS_LIB mstr_standard
J 2
(-1750 2700);
DISPLAY 0.787234 (-1750 2700);
PAINT MONO (-1750 2700);
DISPLAY INVISIBLE (-1750 2700);
FORCEPROP 1 LAST BODY_TYPE PLUMBING
J 2
(-1750 2650);
DISPLAY 1.234043 (-1750 2650);
PAINT GREEN (-1750 2650);
DISPLAY INVISIBLE (-1750 2650);
FORCEPROP 1 LAST HDL_TAP TRUE
J 2
(-2075 2575);
DISPLAY 1.234043 (-2075 2575);
PAINT GREEN (-2075 2575);
DISPLAY INVISIBLE (-2075 2575);
FORCEPROP 1 LAST PATH I96
J 2
(-1750 2700);
DISPLAY 0.936170 (-1750 2700);
PAINT GREEN (-1750 2700);
DISPLAY INVISIBLE (-1750 2700);
FORCEADD TAP..6
R 2
(-1750 2600);
FORCEPROP 3 LASTPIN (-1800 2600) SIG_NAME M_D_DQ<13>
J 0
(-1790 2610);
DISPLAY 0.659574 (-1790 2610);
PAINT MONO (-1790 2610);
DISPLAY INVISIBLE (-1790 2610);
FORCEPROP 1 LASTPIN (-1800 2600) BN 13
J 2
(-1750 2610);
DISPLAY 0.617021 (-1750 2610);
PAINT PINK (-1750 2610);
FORCEPROP 2 LAST CDS_LIB mstr_standard
J 2
(-1750 2600);
DISPLAY 0.787234 (-1750 2600);
PAINT MONO (-1750 2600);
DISPLAY INVISIBLE (-1750 2600);
FORCEPROP 1 LAST BODY_TYPE PLUMBING
J 2
(-1750 2550);
DISPLAY 1.234043 (-1750 2550);
PAINT GREEN (-1750 2550);
DISPLAY INVISIBLE (-1750 2550);
FORCEPROP 1 LAST HDL_TAP TRUE
J 2
(-2075 2475);
DISPLAY 1.234043 (-2075 2475);
PAINT GREEN (-2075 2475);
DISPLAY INVISIBLE (-2075 2475);
FORCEPROP 1 LAST PATH I97
J 2
(-1750 2600);
DISPLAY 0.936170 (-1750 2600);
PAINT GREEN (-1750 2600);
DISPLAY INVISIBLE (-1750 2600);
FORCEADD TAP..6
R 2
(-1750 2650);
FORCEPROP 3 LASTPIN (-1800 2650) SIG_NAME M_D_DQ<12>
J 0
(-1790 2660);
DISPLAY 0.659574 (-1790 2660);
PAINT MONO (-1790 2660);
DISPLAY INVISIBLE (-1790 2660);
FORCEPROP 1 LASTPIN (-1800 2650) BN 12
J 2
(-1750 2660);
DISPLAY 0.617021 (-1750 2660);
PAINT PINK (-1750 2660);
FORCEPROP 2 LAST CDS_LIB mstr_standard
J 2
(-1750 2650);
DISPLAY 0.787234 (-1750 2650);
PAINT MONO (-1750 2650);
DISPLAY INVISIBLE (-1750 2650);
FORCEPROP 1 LAST BODY_TYPE PLUMBING
J 2
(-1750 2600);
DISPLAY 1.234043 (-1750 2600);
PAINT GREEN (-1750 2600);
DISPLAY INVISIBLE (-1750 2600);
FORCEPROP 1 LAST HDL_TAP TRUE
J 2
(-2075 2525);
DISPLAY 1.234043 (-2075 2525);
PAINT GREEN (-2075 2525);
DISPLAY INVISIBLE (-2075 2525);
FORCEPROP 1 LAST PATH I98
J 2
(-1750 2650);
DISPLAY 0.936170 (-1750 2650);
PAINT GREEN (-1750 2650);
DISPLAY INVISIBLE (-1750 2650);
FORCEADD TAP..6
R 2
(-1750 2550);
FORCEPROP 3 LASTPIN (-1800 2550) SIG_NAME M_D_DQ<10>
J 0
(-1790 2560);
DISPLAY 0.659574 (-1790 2560);
PAINT MONO (-1790 2560);
DISPLAY INVISIBLE (-1790 2560);
FORCEPROP 1 LASTPIN (-1800 2550) BN 10
J 2
(-1750 2560);
DISPLAY 0.617021 (-1750 2560);
PAINT PINK (-1750 2560);
FORCEPROP 2 LAST CDS_LIB mstr_standard
J 2
(-1750 2550);
DISPLAY 0.787234 (-1750 2550);
PAINT MONO (-1750 2550);
DISPLAY INVISIBLE (-1750 2550);
FORCEPROP 1 LAST BODY_TYPE PLUMBING
J 2
(-1750 2500);
DISPLAY 1.234043 (-1750 2500);
PAINT GREEN (-1750 2500);
DISPLAY INVISIBLE (-1750 2500);
FORCEPROP 1 LAST HDL_TAP TRUE
J 2
(-2075 2425);
DISPLAY 1.234043 (-2075 2425);
PAINT GREEN (-2075 2425);
DISPLAY INVISIBLE (-2075 2425);
FORCEPROP 1 LAST PATH I99
J 2
(-1750 2550);
DISPLAY 0.936170 (-1750 2550);
PAINT GREEN (-1750 2550);
DISPLAY INVISIBLE (-1750 2550);
FORCEADD BOM_NOTE..1
(-5075 5325);
FORCEPROP 0 LAST L1 STUFF FOR SKU A & B
J 0
(-5225 5225);
DISPLAY 1.063830 (-5225 5225);
PAINT WHITE (-5225 5225);
FORCEPROP 2 LAST BOM_COST SB
J 0
(-5225 5300);
DISPLAY 1.361702 (-5225 5300);
PAINT ORANGE (-5225 5300);
DISPLAY INVISIBLE (-5225 5300);
FORCEPROP 2 LAST CDS_LIB mstr_symbols
J 0
(-5075 5325);
PAINT ORANGE (-5075 5325);
DISPLAY INVISIBLE (-5075 5325);
FORCEPROP 1 LAST COMMENT_BODY TRUE
J 0
(-5050 5425);
DISPLAY 1.319149 (-5050 5425);
PAINT ORANGE (-5050 5425);
DISPLAY INVISIBLE (-5050 5425);
FORCEPROP 2 LAST ROOM SB_HEADERS
J 0
(-5225 5300);
DISPLAY 1.361702 (-5225 5300);
PAINT ORANGE (-5225 5300);
DISPLAY INVISIBLE (-5225 5300);
FORCEADD INTEL_CORP_BPAGE..1
(2650 500);
FORCEPROP 1 LAST CDS_CON_LAST_MODIFIED Tue Dec 01 11:51:29 2015
J 0
(1225 825);
DISPLAY 0.787234 (1225 825);
PAINT ORANGE (1225 825);
DISPLAY INVISIBLE (1225 825);
FORCEPROP 1 LAST CUSTOM_TXT_CDS <CURRENT_DESIGN_SHEET> OF <TOTAL_DESIGN_SHEETS>
J 0
(2150 525);
PAINT GREEN (2150 525);
FORCEPROP 1 LAST CUSTOM_TXT_CDS <CON_LAST_MODIFIED>
J 0
(725 850);
PAINT GREEN (725 850);
FORCEPROP 2 LAST CUSTOM_TXT_CDS <XR_PAGE_TITLE>
J 0
(-5240 5750);
DISPLAY 0.638298 (-5240 5750);
PAINT PINK (-5240 5750);
DISPLAY INVISIBLE (-5240 5750);
FORCEPROP 1 LAST SCH_ADDRESS3 Santa Clara, CA 95052-8119
J 0
(-1325 525);
DISPLAY 0.617021 (-1325 525);
PAINT GREEN (-1325 525);
FORCEPROP 1 LAST SCH_ADDRESS2 P.O. BOX 58119
J 0
(-1325 575);
DISPLAY 0.617021 (-1325 575);
PAINT GREEN (-1325 575);
FORCEPROP 1 LAST SCH_ADDRESS1 2200 Mission College Blvd.
J 0
(-1325 625);
DISPLAY 0.617021 (-1325 625);
PAINT GREEN (-1325 625);
FORCEPROP 1 LAST SCH_TITLE CPU0 DDR4 CH D DIMM0
J 0
(-5300 550);
DISPLAY 1.212766 (-5300 550);
PAINT WHITE (-5300 550);
FORCEPROP 1 LAST SCH_NUMBER H4694802
J 0
(1350 650);
DISPLAY 1.212766 (1350 650);
PAINT YELLOW (1350 650);
FORCEPROP 1 LAST SCH_DEPT BESD
J 1
(-1800 600);
DISPLAY 1.212766 (-1800 600);
PAINT YELLOW (-1800 600);
FORCEPROP 1 LAST SCH_REV 2.420
J 0
(2400 650);
DISPLAY 0.978723 (2400 650);
PAINT YELLOW (2400 650);
FORCEPROP 2 LAST CDS_LIB mstr_symbols
J 0
(2650 500);
DISPLAY 0.787234 (2650 500);
PAINT MONO (2650 500);
DISPLAY INVISIBLE (2650 500);
FORCEPROP 2 LAST PAGE_BORDER TRUE
J 0
(-5240 5750);
DISPLAY 0.680851 (-5240 5750);
PAINT PINK (-5240 5750);
DISPLAY INVISIBLE (-5240 5750);
FORCEPROP 1 LAST COMMENT_BODY TRUE
J 0
(2660 510);
DISPLAY 0.382979 (2660 510);
PAINT GREEN (2660 510);
DISPLAY INVISIBLE (2660 510);
FORCEPROP 2 LAST CDS_XR_PAGE_TITLE CR-49 : @BASEBOARD_FAB2_LIB.BASEBOARD_FAB2(SCH_1):PAGE49
J 0
(-5240 5750);
DISPLAY 0.638298 (-5240 5750);
PAINT PINK (-5240 5750);
DISPLAY INVISIBLE (-5240 5750);
WIRE 17 -1 (950 5075)(950 5175);
WIRE 17 -1 (950 4975)(950 5075);
WIRE 17 -1 (950 5175)(950 5200);
WIRE 17 -1 (1600 5200)(950 5200);
FORCEPROP 2 LAST SIG_NAME M_D_DQS_DN<17:0>
J 0
(1000 5210);
DISPLAY 0.617021 (1000 5210);
PAINT ORANGE (1000 5210);
WIRE 17 -1 (700 5125)(700 5225);
WIRE 17 -1 (700 5025)(700 5125);
WIRE 17 -1 (700 5225)(700 5250);
WIRE 17 -1 (1600 5250)(700 5250);
FORCEPROP 2 LAST SIG_NAME M_D_DQS_DP<17:0>
J 0
(1000 5260);
DISPLAY 0.617021 (1000 5260);
PAINT ORANGE (1000 5260);
WIRE 17 -1 (950 4475)(950 4575);
WIRE 17 -1 (950 4375)(950 4475);
WIRE 17 -1 (950 4575)(950 4675);
WIRE 17 -1 (950 4675)(950 4775);
WIRE 17 -1 (950 4275)(950 4375);
WIRE 17 -1 (950 4175)(950 4275);
WIRE 17 -1 (950 4775)(950 4875);
WIRE 17 -1 (950 4875)(950 4975);
WIRE 17 -1 (950 4075)(950 4175);
WIRE 17 -1 (950 3975)(950 4075);
WIRE 17 -1 (950 3875)(950 3975);
WIRE 17 -1 (950 3775)(950 3875);
WIRE 17 -1 (700 4525)(700 4625);
WIRE 17 -1 (700 4425)(700 4525);
WIRE 17 -1 (700 4625)(700 4725);
WIRE 17 -1 (700 4725)(700 4825);
WIRE 17 -1 (700 4325)(700 4425);
WIRE 17 -1 (700 4225)(700 4325);
WIRE 17 -1 (700 4825)(700 4925);
WIRE 17 -1 (700 4925)(700 5025);
WIRE 17 -1 (700 4125)(700 4225);
WIRE 17 -1 (700 4025)(700 4125);
WIRE 17 -1 (700 3925)(700 4025);
WIRE 17 -1 (700 3825)(700 3925);
WIRE 17 -1 (700 3725)(700 3825);
WIRE 17 -1 (700 3625)(700 3725);
WIRE 17 -1 (700 3525)(700 3625);
WIRE 17 -1 (950 3675)(950 3775);
WIRE 17 -1 (950 3575)(950 3675);
WIRE 17 -1 (950 3475)(950 3575);
WIRE 17 -1 (-1700 5125)(-1700 5175);
WIRE 17 -1 (-1700 5075)(-1700 5125);
WIRE 17 -1 (-1700 5175)(-1700 5200);
WIRE 17 -1 (-1250 5200)(-1700 5200);
FORCEPROP 2 LAST SIG_NAME M_D_DQ<63:0>
J 0
(-1660 5210);
DISPLAY 0.617021 (-1660 5210);
PAINT ORANGE (-1660 5210);
WIRE 17 -1 (-1700 5025)(-1700 5075);
WIRE 17 -1 (-1700 4975)(-1700 5025);
WIRE 17 -1 (-1700 4925)(-1700 4975);
WIRE 17 -1 (-1700 4875)(-1700 4925);
WIRE 17 -1 (-1700 4825)(-1700 4875);
WIRE 17 -1 (-1700 4775)(-1700 4825);
WIRE 17 -1 (-1700 4725)(-1700 4775);
WIRE 17 -1 (-1700 4675)(-1700 4725);
WIRE 17 -1 (-1700 4625)(-1700 4675);
WIRE 17 -1 (-1700 4575)(-1700 4625);
WIRE 17 -1 (-1700 4525)(-1700 4575);
WIRE 17 -1 (-1700 4475)(-1700 4525);
WIRE 17 -1 (-1700 4425)(-1700 4475);
WIRE 17 -1 (-1700 4375)(-1700 4425);
WIRE 17 -1 (-1700 4325)(-1700 4375);
WIRE 17 -1 (-1700 4275)(-1700 4325);
WIRE 17 -1 (-1700 4225)(-1700 4275);
WIRE 17 -1 (-1700 4175)(-1700 4225);
WIRE 17 -1 (-1700 4125)(-1700 4175);
WIRE 17 -1 (-1700 4075)(-1700 4125);
WIRE 17 -1 (-1700 4025)(-1700 4075);
WIRE 17 -1 (-1700 3975)(-1700 4025);
WIRE 17 -1 (-1700 3925)(-1700 3975);
WIRE 17 -1 (-1700 3875)(-1700 3925);
WIRE 17 -1 (-1700 3825)(-1700 3875);
WIRE 17 -1 (-1700 3775)(-1700 3825);
WIRE 17 -1 (-1700 3725)(-1700 3775);
WIRE 17 -1 (-1700 3675)(-1700 3725);
WIRE 17 -1 (-1700 3625)(-1700 3675);
WIRE 17 -1 (-1700 3575)(-1700 3625);
WIRE 17 -1 (-1700 3525)(-1700 3575);
WIRE 17 -1 (-1700 3475)(-1700 3525);
WIRE 17 -1 (-1700 3425)(-1700 3475);
WIRE 17 -1 (-1700 3375)(-1700 3425);
WIRE 17 -1 (-1700 3325)(-1700 3375);
WIRE 17 -1 (-1700 3275)(-1700 3325);
WIRE 17 -1 (-1700 3225)(-1700 3275);
WIRE 17 -1 (-1700 3175)(-1700 3225);
WIRE 17 -1 (-1700 3125)(-1700 3175);
WIRE 17 -1 (-1700 3075)(-1700 3125);
WIRE 17 -1 (-3300 4075)(-3300 4125);
WIRE 17 -1 (-3300 4150)(-3300 4125);
WIRE 17 -1 (-3950 4150)(-3300 4150);
FORCEPROP 2 LAST SIG_NAME M_D_BG<1:0>
J 0
(-3925 4160);
DISPLAY 0.617021 (-3925 4160);
PAINT ORANGE (-3925 4160);
WIRE 17 -1 (-3300 4475)(-3300 4525);
WIRE 17 -1 (-3300 4425)(-3300 4475);
WIRE 17 -1 (-3300 4525)(-3300 4575);
WIRE 17 -1 (-3300 4575)(-3300 4625);
WIRE 17 -1 (-3300 4375)(-3300 4425);
WIRE 17 -1 (-3300 4325)(-3300 4375);
WIRE 17 -1 (-3300 4625)(-3300 4675);
WIRE 17 -1 (-3300 4675)(-3300 4725);
WIRE 17 -1 (-3300 4725)(-3300 4775);
WIRE 17 -1 (-3300 4775)(-3300 4825);
WIRE 17 -1 (-3300 4825)(-3300 4875);
WIRE 17 -1 (-3300 4875)(-3300 4925);
WIRE 17 -1 (-3300 4925)(-3300 4975);
WIRE 17 -1 (-3300 4975)(-3300 5025);
WIRE 17 -1 (-3300 5025)(-3300 5075);
WIRE 17 -1 (-3300 5075)(-3300 5125);
WIRE 17 -1 (-3300 5125)(-3300 5175);
WIRE 17 -1 (-3300 5175)(-3300 5200);
WIRE 17 -1 (-3950 5200)(-3300 5200);
FORCEPROP 2 LAST SIG_NAME M_D_MA<17:0>
J 0
(-3925 5210);
DISPLAY 0.617021 (-3925 5210);
PAINT ORANGE (-3925 5210);
WIRE 17 -1 (-3300 4175)(-3300 4225);
WIRE 17 -1 (-3300 4250)(-3300 4225);
WIRE 17 -1 (-3300 4250)(-3950 4250);
FORCEPROP 2 LAST SIG_NAME M_D_BA<1:0>
J 0
(-3925 4260);
DISPLAY 0.617021 (-3925 4260);
PAINT ORANGE (-3925 4260);
WIRE 17 -1 (-1700 3025)(-1700 3075);
WIRE 17 -1 (-1700 2975)(-1700 3025);
WIRE 17 -1 (-1700 2925)(-1700 2975);
WIRE 17 -1 (-1700 2875)(-1700 2925);
WIRE 17 -1 (-1700 2825)(-1700 2875);
WIRE 17 -1 (-1700 2775)(-1700 2825);
WIRE 17 -1 (-1700 2725)(-1700 2775);
WIRE 17 -1 (-1700 2675)(-1700 2725);
WIRE 17 -1 (-1700 2625)(-1700 2675);
WIRE 17 -1 (-1700 2575)(-1700 2625);
WIRE 17 -1 (-1700 2525)(-1700 2575);
WIRE 17 -1 (-1700 2475)(-1700 2525);
WIRE 17 -1 (-1700 2425)(-1700 2475);
WIRE 17 -1 (-1700 2375)(-1700 2425);
WIRE 17 -1 (-1700 2325)(-1700 2375);
WIRE 17 -1 (-1700 2275)(-1700 2325);
WIRE 17 -1 (-1700 2225)(-1700 2275);
WIRE 17 -1 (-1700 2175)(-1700 2225);
WIRE 17 -1 (-1700 2125)(-1700 2175);
WIRE 17 -1 (-1700 2075)(-1700 2125);
WIRE 17 -1 (-1700 2025)(-1700 2075);
WIRE 17 -1 (-3300 3875)(-3300 3975);
WIRE 17 -1 (-3300 4000)(-3300 3975);
WIRE 17 -1 (-3300 4000)(-3950 4000);
FORCEPROP 2 LAST SIG_NAME M_D_CLK_DP<3:0>
J 0
(-3900 4010);
DISPLAY 0.617021 (-3900 4010);
PAINT ORANGE (-3900 4010);
WIRE 17 -1 (-3500 3950)(-3500 3925);
WIRE 17 -1 (-3500 3950)(-3950 3950);
FORCEPROP 2 LAST SIG_NAME M_D_CLK_DN<3:0>
J 0
(-3900 3960);
DISPLAY 0.617021 (-3900 3960);
PAINT ORANGE (-3900 3960);
WIRE 17 -1 (-3300 3375)(-3300 3425);
WIRE 17 -1 (-3300 3425)(-3300 3450);
WIRE 17 -1 (-3300 3450)(-3950 3450);
FORCEPROP 2 LAST SIG_NAME M_D_CKE<3:0>
J 0
(-3925 3460);
DISPLAY 0.617021 (-3925 3460);
PAINT ORANGE (-3925 3460);
WIRE 17 -1 (-3300 3625)(-3300 3675);
WIRE 17 -1 (-3300 3575)(-3300 3625);
WIRE 17 -1 (-3300 3700)(-3300 3675);
WIRE 17 -1 (-3300 3700)(-3950 3700);
FORCEPROP 2 LAST SIG_NAME M_D_CS_N<7:0>
J 0
(-3925 3710);
DISPLAY 0.617021 (-3925 3710);
PAINT ORANGE (-3925 3710);
WIRE 17 -1 (-3300 3525)(-3300 3575);
WIRE 17 -1 (-3300 3025)(-3300 3075);
WIRE 17 -1 (-3300 2975)(-3300 3025);
WIRE 17 -1 (-3300 3075)(-3300 3125);
WIRE 17 -1 (-3300 3125)(-3300 3150);
WIRE 17 -1 (-3300 2925)(-3300 2975);
WIRE 17 -1 (-3300 2875)(-3300 2925);
WIRE 17 -1 (-3300 3150)(-3950 3150);
FORCEPROP 2 LAST SIG_NAME M_D_ECC<7:0>
J 0
(-3925 3160);
DISPLAY 0.617021 (-3925 3160);
PAINT ORANGE (-3925 3160);
WIRE 17 -1 (-3300 2825)(-3300 2875);
WIRE 17 -1 (-3300 2775)(-3300 2825);
WIRE 17 -1 (-3500 3925)(-3500 3825);
WIRE 17 -1 (-3300 3225)(-3300 3275);
WIRE 17 -1 (-3300 3275)(-3300 3300);
WIRE 17 -1 (-3300 3300)(-3950 3300);
FORCEPROP 2 LAST SIG_NAME M_D_ODT<3:0>
J 0
(-3925 3310);
DISPLAY 0.617021 (-3925 3310);
PAINT ORANGE (-3925 3310);
WIRE 16 -1 (-750 1100)(-550 1100);
WIRE 16 -1 (-750 1100)(-750 1150);
WIRE 16 -1 (-750 1150)(-550 1150);
WIRE 16 -1 (-750 1150)(-750 1200);
WIRE 16 -1 (-750 1200)(-550 1200);
WIRE 16 -1 (-750 1200)(-750 1250);
WIRE 16 -1 (-750 1250)(-750 1300);
WIRE 16 -1 (-750 1250)(-550 1250);
WIRE 16 -1 (-750 1300)(-550 1300);
WIRE 16 -1 (-750 1300)(-750 1350);
WIRE 16 -1 (-750 1350)(-550 1350);
WIRE 16 -1 (-750 1350)(-750 1400);
WIRE 16 -1 (-750 1400)(-550 1400);
WIRE 16 -1 (-750 1400)(-750 1450);
WIRE 16 -1 (-750 1450)(-550 1450);
WIRE 16 -1 (-750 1450)(-750 1500);
WIRE 16 -1 (-750 1500)(-750 1550);
WIRE 16 -1 (-750 1500)(-550 1500);
WIRE 16 -1 (-750 1550)(-550 1550);
WIRE 16 -1 (-750 1550)(-750 1600);
WIRE 16 -1 (-750 1600)(-550 1600);
WIRE 16 -1 (-750 1600)(-750 1650);
WIRE 16 -1 (-750 1650)(-550 1650);
WIRE 16 -1 (-750 1650)(-750 1700);
WIRE 16 -1 (-750 1700)(-550 1700);
WIRE 16 -1 (-750 1700)(-750 1750);
WIRE 16 -1 (-750 1750)(-750 1800);
WIRE 16 -1 (-750 1750)(-550 1750);
WIRE 16 -1 (-750 1800)(-550 1800);
WIRE 16 -1 (-750 1800)(-750 1850);
WIRE 16 -1 (-750 1850)(-550 1850);
WIRE 16 -1 (-750 1850)(-750 1900);
WIRE 16 -1 (-750 1900)(-550 1900);
WIRE 16 -1 (-750 1900)(-750 1950);
WIRE 16 -1 (-750 1950)(-550 1950);
WIRE 16 -1 (-750 1950)(-750 2000);
WIRE 16 -1 (-750 2000)(-750 2050);
WIRE 16 -1 (-750 2000)(-550 2000);
WIRE 16 -1 (-750 2050)(-550 2050);
WIRE 16 -1 (-750 2050)(-750 2100);
WIRE 16 -1 (-750 2100)(-550 2100);
WIRE 16 -1 (-750 2100)(-750 2150);
WIRE 16 -1 (-750 2150)(-550 2150);
WIRE 16 -1 (-750 2150)(-750 2200);
WIRE 16 -1 (-750 2200)(-550 2200);
WIRE 16 -1 (-750 2200)(-750 2250);
WIRE 16 -1 (-750 2250)(-550 2250);
WIRE 16 -1 (-750 2250)(-750 2300);
WIRE 16 -1 (-750 2300)(-750 2350);
WIRE 16 -1 (-750 2300)(-550 2300);
WIRE 16 -1 (-750 2350)(-550 2350);
WIRE 16 -1 (-1225 2350)(-750 2350);
WIRE 16 -1 (-1225 2425)(-1225 2350);
WIRE 16 -1 (-750 2450)(-550 2450);
WIRE 16 -1 (-750 2450)(-750 2500);
WIRE 16 -1 (-750 2500)(-550 2500);
WIRE 16 -1 (-925 2500)(-750 2500);
WIRE 16 -1 (-925 2600)(-925 2500);
WIRE 16 -1 (2500 3600)(2300 3600);
WIRE 16 -1 (2500 3550)(2500 3600);
WIRE 16 -1 (2500 3500)(2500 3550);
WIRE 16 -1 (2500 3550)(2300 3550);
WIRE 16 -1 (2300 3500)(2500 3500);
WIRE 16 -1 (2500 3450)(2500 3500);
WIRE 16 -1 (2500 3400)(2500 3450);
WIRE 16 -1 (2500 3450)(2300 3450);
WIRE 16 -1 (2300 3400)(2500 3400);
WIRE 16 -1 (2500 3350)(2500 3400);
WIRE 16 -1 (2500 3300)(2500 3350);
WIRE 16 -1 (2500 3350)(2300 3350);
WIRE 16 -1 (2300 3300)(2500 3300);
WIRE 16 -1 (2500 3250)(2500 3300);
WIRE 16 -1 (2500 3200)(2500 3250);
WIRE 16 -1 (2500 3250)(2300 3250);
WIRE 16 -1 (2300 3200)(2500 3200);
WIRE 16 -1 (2500 3150)(2500 3200);
WIRE 16 -1 (2500 3100)(2500 3150);
WIRE 16 -1 (2500 3150)(2300 3150);
WIRE 16 -1 (2300 3100)(2500 3100);
WIRE 16 -1 (2500 3050)(2500 3100);
WIRE 16 -1 (2500 3000)(2500 3050);
WIRE 16 -1 (2500 3050)(2300 3050);
WIRE 16 -1 (2300 3000)(2500 3000);
WIRE 16 -1 (2500 2950)(2500 3000);
WIRE 16 -1 (2500 2900)(2500 2950);
WIRE 16 -1 (2500 2950)(2300 2950);
WIRE 16 -1 (2300 2900)(2500 2900);
WIRE 16 -1 (2500 2850)(2500 2900);
WIRE 16 -1 (2500 2800)(2500 2850);
WIRE 16 -1 (2500 2850)(2300 2850);
WIRE 16 -1 (2300 2800)(2500 2800);
WIRE 16 -1 (2500 2750)(2500 2800);
WIRE 16 -1 (2500 2700)(2500 2750);
WIRE 16 -1 (2500 2750)(2300 2750);
WIRE 16 -1 (2300 2700)(2500 2700);
WIRE 16 -1 (2500 2650)(2500 2700);
WIRE 16 -1 (2500 2600)(2500 2650);
WIRE 16 -1 (2500 2650)(2300 2650);
WIRE 16 -1 (2300 2600)(2500 2600);
WIRE 16 -1 (2500 2550)(2500 2600);
WIRE 16 -1 (2500 2500)(2500 2550);
WIRE 16 -1 (2500 2550)(2300 2550);
WIRE 16 -1 (2300 2500)(2500 2500);
WIRE 16 -1 (2500 2450)(2500 2500);
WIRE 16 -1 (2500 2400)(2500 2450);
WIRE 16 -1 (2500 2450)(2300 2450);
WIRE 16 -1 (2300 2400)(2500 2400);
WIRE 16 -1 (2500 2350)(2500 2400);
WIRE 16 -1 (2500 2300)(2500 2350);
WIRE 16 -1 (2500 2350)(2300 2350);
WIRE 16 -1 (2300 2300)(2500 2300);
WIRE 16 -1 (2500 2250)(2500 2300);
WIRE 16 -1 (2500 2200)(2500 2250);
WIRE 16 -1 (2500 2250)(2300 2250);
WIRE 16 -1 (2500 2150)(2500 2200);
WIRE 16 -1 (2500 2200)(2300 2200);
WIRE 16 -1 (2300 2150)(2500 2150);
WIRE 16 -1 (2500 2100)(2500 2150);
WIRE 16 -1 (2500 2050)(2500 2100);
WIRE 16 -1 (2500 2100)(2300 2100);
WIRE 16 -1 (2300 2050)(2500 2050);
WIRE 16 -1 (2500 2000)(2500 2050);
WIRE 16 -1 (2500 1950)(2500 2000);
WIRE 16 -1 (2500 2000)(2300 2000);
WIRE 16 -1 (2300 1950)(2500 1950);
WIRE 16 -1 (2500 1900)(2500 1950);
WIRE 16 -1 (2500 1850)(2500 1900);
WIRE 16 -1 (2500 1900)(2300 1900);
WIRE 16 -1 (2300 1850)(2500 1850);
WIRE 16 -1 (2500 1800)(2500 1850);
WIRE 16 -1 (2300 1800)(2500 1800);
WIRE 16 -1 (2500 1750)(2500 1800);
WIRE 16 -1 (2500 1700)(2500 1750);
WIRE 16 -1 (2500 1750)(2300 1750);
WIRE 16 -1 (2500 1650)(2500 1700);
WIRE 16 -1 (2500 1700)(2300 1700);
WIRE 16 -1 (2500 1600)(2500 1650);
WIRE 16 -1 (2500 1650)(2300 1650);
WIRE 16 -1 (2300 1600)(2500 1600);
WIRE 16 -1 (2500 1550)(2500 1600);
WIRE 16 -1 (2500 1550)(2300 1550);
WIRE 16 -1 (2500 1500)(2500 1550);
WIRE 16 -1 (2300 1500)(2500 1500);
WIRE 16 -1 (2500 1450)(2500 1500);
WIRE 16 -1 (2500 1400)(2500 1450);
WIRE 16 -1 (2500 1450)(2300 1450);
WIRE 16 -1 (2500 1350)(2500 1400);
WIRE 16 -1 (2500 1400)(2300 1400);
WIRE 16 -1 (2300 1350)(2500 1350);
WIRE 16 -1 (2500 1300)(2500 1350);
WIRE 16 -1 (2500 1300)(2500 1200);
WIRE 16 -1 (2500 1300)(2300 1300);
WIRE 16 -1 (-3300 2300)(-3000 2300);
WIRE 16 -1 (-3300 2300)(-3300 2250);
WIRE 16 -1 (-3300 2250)(-3000 2250);
WIRE 16 -1 (-3300 2250)(-3300 2200);
WIRE 16 -1 (-3000 2200)(-3300 2200);
WIRE 16 -1 (-3300 2200)(-5100 2200);
FORCEPROP 2 LAST ROOM TBD
J 0
(-3650 2250);
PAINT ORANGE (-3650 2250);
DISPLAY INVISIBLE (-3650 2250);
FORCEPROP 2 LAST BOM_COST TBD
J 0
(-3650 2250);
PAINT ORANGE (-3650 2250);
DISPLAY INVISIBLE (-3650 2250);
WIRE 16 -1 (-5100 2200)(-5100 2150);
WIRE 16 -1 (-4650 1700)(-4650 1600);
WIRE 16 -1 (-750 2600)(-550 2600);
WIRE 16 -1 (-750 2650)(-750 2600);
WIRE 16 -1 (-750 2650)(-550 2650);
WIRE 16 -1 (-750 2700)(-750 2650);
WIRE 16 -1 (-550 2700)(-750 2700);
WIRE 16 -1 (-750 2750)(-750 2700);
WIRE 16 -1 (-750 2750)(-550 2750);
WIRE 16 -1 (-750 2800)(-750 2750);
WIRE 16 -1 (-750 2900)(-750 2800);
WIRE 16 -1 (-750 2800)(-550 2800);
WIRE 16 -1 (-3000 2350)(-5100 2350);
WIRE 16 -1 (-5100 2450)(-5100 2350);
WIRE 16 -1 (450 2750)(650 2750);
WIRE 16 -1 (650 2750)(650 2800);
WIRE 16 -1 (450 2800)(650 2800);
WIRE 16 -1 (650 2800)(650 2975);
WIRE 16 -1 (1100 3600)(1300 3600);
WIRE 16 -1 (1100 3550)(1100 3600);
WIRE 16 -1 (1100 3550)(1300 3550);
WIRE 16 -1 (1100 3500)(1100 3550);
WIRE 16 -1 (1300 3500)(1100 3500);
WIRE 16 -1 (1100 3450)(1100 3500);
WIRE 16 -1 (1100 3450)(1300 3450);
WIRE 16 -1 (1100 3400)(1100 3450);
WIRE 16 -1 (1300 3400)(1100 3400);
WIRE 16 -1 (1100 3350)(1100 3400);
WIRE 16 -1 (1100 3350)(1300 3350);
WIRE 16 -1 (1100 3300)(1100 3350);
WIRE 16 -1 (1300 3300)(1100 3300);
WIRE 16 -1 (1100 3250)(1100 3300);
WIRE 16 -1 (1100 3250)(1300 3250);
WIRE 16 -1 (1100 3200)(1100 3250);
WIRE 16 -1 (1300 3200)(1100 3200);
WIRE 16 -1 (1100 3150)(1100 3200);
WIRE 16 -1 (1100 3150)(1300 3150);
WIRE 16 -1 (1100 3100)(1100 3150);
WIRE 16 -1 (1300 3100)(1100 3100);
WIRE 16 -1 (1100 3050)(1100 3100);
WIRE 16 -1 (1100 3050)(1300 3050);
WIRE 16 -1 (1100 3000)(1100 3050);
WIRE 16 -1 (1300 3000)(1100 3000);
WIRE 16 -1 (1100 2950)(1100 3000);
WIRE 16 -1 (1100 2950)(1300 2950);
WIRE 16 -1 (1100 2900)(1100 2950);
WIRE 16 -1 (1300 2900)(1100 2900);
WIRE 16 -1 (1100 2850)(1100 2900);
WIRE 16 -1 (1100 2850)(1300 2850);
WIRE 16 -1 (1100 2800)(1100 2850);
WIRE 16 -1 (1300 2800)(1100 2800);
WIRE 16 -1 (1100 2750)(1100 2800);
WIRE 16 -1 (1100 2750)(1300 2750);
WIRE 16 -1 (1100 2700)(1100 2750);
WIRE 16 -1 (1300 2700)(1100 2700);
WIRE 16 -1 (1100 2650)(1100 2700);
WIRE 16 -1 (1100 2650)(1300 2650);
WIRE 16 -1 (1100 2600)(1100 2650);
WIRE 16 -1 (1300 2600)(1100 2600);
WIRE 16 -1 (1100 2550)(1100 2600);
WIRE 16 -1 (1100 2550)(1300 2550);
WIRE 16 -1 (1100 2500)(1100 2550);
WIRE 16 -1 (1300 2500)(1100 2500);
WIRE 16 -1 (1100 2450)(1100 2500);
WIRE 16 -1 (1100 2450)(1300 2450);
WIRE 16 -1 (1100 2400)(1100 2450);
WIRE 16 -1 (1300 2400)(1100 2400);
WIRE 16 -1 (1100 2350)(1100 2400);
WIRE 16 -1 (1100 2350)(1300 2350);
WIRE 16 -1 (1100 2300)(1100 2350);
WIRE 16 -1 (1300 2300)(1100 2300);
WIRE 16 -1 (1100 2250)(1100 2300);
WIRE 16 -1 (1100 2250)(1300 2250);
WIRE 16 -1 (1100 2200)(1100 2250);
WIRE 16 -1 (1100 2200)(1300 2200);
WIRE 16 -1 (1100 2150)(1100 2200);
WIRE 16 -1 (1300 2150)(1100 2150);
WIRE 16 -1 (1100 2100)(1100 2150);
WIRE 16 -1 (1100 2100)(1300 2100);
WIRE 16 -1 (1100 2050)(1100 2100);
WIRE 16 -1 (1300 2050)(1100 2050);
WIRE 16 -1 (1100 2000)(1100 2050);
WIRE 16 -1 (1100 2000)(1300 2000);
WIRE 16 -1 (1100 1950)(1100 2000);
WIRE 16 -1 (1300 1950)(1100 1950);
WIRE 16 -1 (1100 1900)(1100 1950);
WIRE 16 -1 (1100 1900)(1300 1900);
WIRE 16 -1 (1100 1850)(1100 1900);
WIRE 16 -1 (1300 1850)(1100 1850);
WIRE 16 -1 (1100 1800)(1100 1850);
WIRE 16 -1 (1300 1800)(1100 1800);
WIRE 16 -1 (1100 1750)(1100 1800);
WIRE 16 -1 (1100 1750)(1300 1750);
WIRE 16 -1 (1100 1700)(1100 1750);
WIRE 16 -1 (1100 1700)(1300 1700);
WIRE 16 -1 (1100 1650)(1100 1700);
WIRE 16 -1 (1100 1650)(1300 1650);
WIRE 16 -1 (1100 1600)(1100 1650);
WIRE 16 -1 (1300 1600)(1100 1600);
WIRE 16 -1 (1100 1550)(1100 1600);
WIRE 16 -1 (1100 1550)(1300 1550);
WIRE 16 -1 (1100 1500)(1100 1550);
WIRE 16 -1 (1300 1500)(1100 1500);
WIRE 16 -1 (1100 1450)(1100 1500);
WIRE 16 -1 (1100 1450)(1300 1450);
WIRE 16 -1 (1100 1400)(1100 1450);
WIRE 16 -1 (1100 1400)(1300 1400);
WIRE 16 -1 (1100 1350)(1100 1400);
WIRE 16 -1 (1300 1350)(1100 1350);
WIRE 16 -1 (1100 1300)(1100 1350);
WIRE 16 -1 (1100 1300)(1300 1300);
WIRE 16 -1 (1100 1300)(1100 1200);
WIRE 16 -1 (-4650 1900)(-4650 2000);
WIRE 16 -1 (-3000 2000)(-4650 2000);
FORCEPROP 2 LAST SIG_NAME M_D_VREF
J 0
(-3750 2010);
DISPLAY 0.617021 (-3750 2010);
PAINT ORANGE (-3750 2010);
WIRE 16 -1 (-4750 2000)(-4650 2000);
WIRE 16 -1 (-3850 1850)(-3000 1850);
FORCEPROP 2 LAST SIG_NAME TP_CH_D_DIMM_D0_RFU_1
J 0
(-3800 1860);
DISPLAY 0.617021 (-3800 1860);
PAINT ORANGE (-3800 1860);
FORCEPROP 2 LASTPROP $XRERR UNIQUE?
J 0
(-4090 1850);
DISPLAY 0.638298 (-4090 1850);
PAINT MONO (-4090 1850);
DISPLAY INVISIBLE (-4090 1850);
WIRE 16 -1 (-3850 1800)(-3000 1800);
FORCEPROP 2 LAST SIG_NAME TP_CH_D_DIMM_D0_RFU_0
J 0
(-3800 1810);
DISPLAY 0.617021 (-3800 1810);
PAINT ORANGE (-3800 1810);
FORCEPROP 2 LASTPROP $XRERR UNIQUE?
J 0
(-4090 1800);
DISPLAY 0.638298 (-4090 1800);
PAINT MONO (-4090 1800);
DISPLAY INVISIBLE (-4090 1800);
WIRE 16 -1 (-3850 1900)(-3000 1900);
FORCEPROP 2 LAST SIG_NAME TP_CH_D_DIMM_D0_RFU_2
J 0
(-3800 1910);
DISPLAY 0.617021 (-3800 1910);
PAINT ORANGE (-3800 1910);
FORCEPROP 2 LASTPROP $XRERR UNIQUE?
J 0
(-4090 1900);
DISPLAY 0.638298 (-4090 1900);
PAINT MONO (-4090 1900);
DISPLAY INVISIBLE (-4090 1900);
WIRE 16 -1 (-3850 1700)(-3000 1700);
FORCEPROP 2 LAST SIG_NAME FM_ADR_COMPLETE_DEF_N
J 0
(-3800 1710);
DISPLAY 0.617021 (-3800 1710);
PAINT ORANGE (-3800 1710);
WIRE 16 -1 (-3450 2550)(-3000 2550);
WIRE 16 -1 (-3450 2550)(-3450 2850);
WIRE 16 -1 (-3450 2850)(-4175 2850);
FORCEPROP 2 LAST SIG_NAME FM_DIMM_EVENT_COD_N
J 0
(-4169 2870);
DISPLAY 0.617021 (-4169 2870);
PAINT ORANGE (-4169 2870);
WIRE 16 -1 (-3000 2600)(-3400 2600);
WIRE 16 -1 (-3400 2600)(-3400 3050);
WIRE 16 -1 (-3400 3050)(-3950 3050);
FORCEPROP 2 LAST SIG_NAME M_DEF_RST_N
J 0
(-3925 3060);
DISPLAY 0.617021 (-3925 3060);
PAINT ORANGE (-3925 3060);
WIRE 16 -1 (-3000 2650)(-3350 2650);
WIRE 16 -1 (-3350 2650)(-3350 3100);
WIRE 16 -1 (-3350 3100)(-3950 3100);
FORCEPROP 2 LAST SIG_NAME M_D_PAR
J 0
(-3925 3110);
DISPLAY 0.617021 (-3925 3110);
PAINT ORANGE (-3925 3110);
WIRE 16 -1 (-3150 3700)(-3000 3700);
WIRE 16 -1 (-3150 3750)(-3150 3700);
WIRE 16 -1 (-3150 3750)(-3950 3750);
FORCEPROP 2 LAST SIG_NAME M_D_C<2>
J 0
(-3925 3760);
DISPLAY 0.617021 (-3925 3760);
PAINT ORANGE (-3925 3760);
WIRE 16 -1 (-3000 3500)(-3200 3500);
WIRE 16 -1 (-3000 3250)(-3200 3250);
WIRE 16 -1 (-3000 3200)(-3200 3200);
WIRE 16 -1 (-3000 3100)(-3200 3100);
WIRE 16 -1 (-3000 3400)(-3200 3400);
WIRE 16 -1 (-3000 3800)(-3400 3800);
WIRE 16 -1 (-3000 2750)(-3200 2750);
WIRE 16 -1 (-3000 2800)(-3200 2800);
WIRE 16 -1 (-3000 2850)(-3200 2850);
WIRE 16 -1 (-3000 2900)(-3200 2900);
WIRE 16 -1 (-3000 2950)(-3200 2950);
WIRE 16 -1 (-3000 3000)(-3200 3000);
WIRE 16 -1 (-3000 3050)(-3200 3050);
WIRE 16 -1 (-3000 3550)(-3200 3550);
WIRE 16 -1 (-3000 3600)(-3200 3600);
WIRE 16 -1 (-3000 3650)(-3200 3650);
WIRE 16 -1 (-3000 3350)(-3200 3350);
WIRE 16 -1 (-3000 4050)(-3200 4050);
WIRE 16 -1 (-3000 3950)(-3200 3950);
WIRE 16 -1 (-3000 3900)(-3400 3900);
WIRE 16 -1 (-3000 3850)(-3200 3850);
WIRE 16 -1 (-3000 2450)(-3950 2450);
FORCEPROP 2 LAST SIG_NAME M_D_ACT_N
J 0
(-3900 2460);
DISPLAY 0.617021 (-3900 2460);
PAINT ORANGE (-3900 2460);
WIRE 16 -1 (-3000 2500)(-3975 2500);
FORCEPROP 2 LAST SIG_NAME M_D_ALERT_N
J 0
(-3925 2510);
DISPLAY 0.617021 (-3925 2510);
PAINT ORANGE (-3925 2510);
WIRE 16 -1 (-3000 2150)(-3800 2150);
WIRE 16 -1 (-3800 2100)(-3000 2100);
FORCEPROP 2 LAST SIG_NAME SMB_DDR_DEF_VPP_SCL
J 0
(-3760 2110);
DISPLAY 0.617021 (-3760 2110);
PAINT ORANGE (-3760 2110);
WIRE 16 -1 (-1800 2000)(-2000 2000);
WIRE 16 -1 (-1800 2250)(-2000 2250);
WIRE 16 -1 (-1800 2200)(-2000 2200);
WIRE 16 -1 (-1800 2150)(-2000 2150);
WIRE 16 -1 (-1800 2100)(-2000 2100);
WIRE 16 -1 (-1800 2050)(-2000 2050);
WIRE 16 -1 (-1800 2300)(-2000 2300);
WIRE 16 -1 (-1800 2400)(-2000 2400);
WIRE 16 -1 (-1800 2450)(-2000 2450);
WIRE 16 -1 (-1800 2500)(-2000 2500);
WIRE 16 -1 (-1800 2550)(-2000 2550);
WIRE 16 -1 (-1800 2350)(-2000 2350);
WIRE 16 -1 (-1800 2750)(-2000 2750);
WIRE 16 -1 (-1800 2600)(-2000 2600);
WIRE 16 -1 (-1800 2650)(-2000 2650);
WIRE 16 -1 (-1800 2700)(-2000 2700);
WIRE 16 -1 (-1800 2800)(-2000 2800);
WIRE 16 -1 (-1800 2850)(-2000 2850);
WIRE 16 -1 (-1800 2900)(-2000 2900);
WIRE 16 -1 (-1800 2950)(-2000 2950);
WIRE 16 -1 (-1800 3000)(-2000 3000);
WIRE 16 -1 (-1800 3050)(-2000 3050);
WIRE 16 -1 (-1800 3300)(-2000 3300);
WIRE 16 -1 (-1800 3100)(-2000 3100);
WIRE 16 -1 (-1800 3150)(-2000 3150);
WIRE 16 -1 (-1800 3200)(-2000 3200);
WIRE 16 -1 (-1800 3250)(-2000 3250);
WIRE 16 -1 (-1800 3350)(-2000 3350);
WIRE 16 -1 (-1800 3500)(-2000 3500);
WIRE 16 -1 (-1800 3550)(-2000 3550);
WIRE 16 -1 (-1800 3400)(-2000 3400);
WIRE 16 -1 (-1800 3450)(-2000 3450);
WIRE 16 -1 (-1800 3800)(-2000 3800);
WIRE 16 -1 (-1800 3750)(-2000 3750);
WIRE 16 -1 (-1800 3600)(-2000 3600);
WIRE 16 -1 (-1800 3650)(-2000 3650);
WIRE 16 -1 (-1800 3700)(-2000 3700);
WIRE 16 -1 (-1800 3900)(-2000 3900);
WIRE 16 -1 (-1800 3850)(-2000 3850);
WIRE 16 -1 (-1800 3950)(-2000 3950);
WIRE 16 -1 (-1800 4000)(-2000 4000);
WIRE 16 -1 (-1800 4050)(-2000 4050);
WIRE 16 -1 (-3000 5100)(-3200 5100);
WIRE 16 -1 (-3000 5050)(-3200 5050);
WIRE 16 -1 (-3000 5000)(-3200 5000);
WIRE 16 -1 (-3000 4850)(-3200 4850);
WIRE 16 -1 (-3000 4800)(-3200 4800);
WIRE 16 -1 (-3000 4400)(-3200 4400);
WIRE 16 -1 (-3000 4150)(-3200 4150);
WIRE 16 -1 (-3000 4750)(-3200 4750);
WIRE 16 -1 (-3000 4700)(-3200 4700);
WIRE 16 -1 (-3000 4650)(-3200 4650);
WIRE 16 -1 (-3000 4600)(-3200 4600);
WIRE 16 -1 (-3000 4550)(-3200 4550);
WIRE 16 -1 (-3000 4450)(-3200 4450);
WIRE 16 -1 (-3000 5150)(-3200 5150);
WIRE 16 -1 (-3000 4950)(-3200 4950);
WIRE 16 -1 (-3000 4900)(-3200 4900);
WIRE 16 -1 (-3000 4350)(-3200 4350);
WIRE 16 -1 (-3000 4300)(-3200 4300);
WIRE 16 -1 (-3000 4200)(-3200 4200);
WIRE 16 -1 (-3000 4500)(-3200 4500);
WIRE 16 -1 (-3000 4100)(-3200 4100);
WIRE 16 -1 (-1800 4350)(-2000 4350);
WIRE 16 -1 (-1800 4100)(-2000 4100);
WIRE 16 -1 (-1800 4150)(-2000 4150);
WIRE 16 -1 (-1800 4200)(-2000 4200);
WIRE 16 -1 (-1800 4250)(-2000 4250);
WIRE 16 -1 (-1800 4300)(-2000 4300);
WIRE 16 -1 (-1800 4400)(-2000 4400);
WIRE 16 -1 (-1800 4450)(-2000 4450);
WIRE 16 -1 (-1800 4500)(-2000 4500);
WIRE 16 -1 (-1800 4550)(-2000 4550);
WIRE 16 -1 (-1800 4600)(-2000 4600);
WIRE 16 -1 (-1800 4650)(-2000 4650);
WIRE 16 -1 (-1800 4700)(-2000 4700);
WIRE 16 -1 (-1800 4850)(-2000 4850);
WIRE 16 -1 (-1800 4750)(-2000 4750);
WIRE 16 -1 (-1800 4800)(-2000 4800);
WIRE 16 -1 (-1800 5100)(-2000 5100);
WIRE 16 -1 (-1800 5050)(-2000 5050);
WIRE 16 -1 (-1800 4900)(-2000 4900);
WIRE 16 -1 (-1800 4950)(-2000 4950);
WIRE 16 -1 (-1800 5000)(-2000 5000);
WIRE 16 -1 (-1800 5150)(-2000 5150);
WIRE 16 -1 (850 4050)(400 4050);
WIRE 16 -1 (600 4000)(400 4000);
WIRE 16 -1 (850 3950)(400 3950);
WIRE 16 -1 (600 3900)(400 3900);
WIRE 16 -1 (850 3850)(400 3850);
WIRE 16 -1 (600 3800)(400 3800);
WIRE 16 -1 (850 3750)(400 3750);
WIRE 16 -1 (600 3700)(400 3700);
WIRE 16 -1 (850 3650)(400 3650);
WIRE 16 -1 (600 3600)(400 3600);
WIRE 16 -1 (850 3550)(400 3550);
WIRE 16 -1 (600 3500)(400 3500);
WIRE 16 -1 (850 3450)(400 3450);
WIRE 16 -1 (600 4400)(400 4400);
WIRE 16 -1 (850 4350)(400 4350);
WIRE 16 -1 (600 4300)(400 4300);
WIRE 16 -1 (850 4250)(400 4250);
WIRE 16 -1 (600 4200)(400 4200);
WIRE 16 -1 (850 4150)(400 4150);
WIRE 16 -1 (600 4100)(400 4100);
WIRE 16 -1 (600 5100)(400 5100);
WIRE 16 -1 (850 5050)(400 5050);
WIRE 16 -1 (600 5000)(400 5000);
WIRE 16 -1 (850 4950)(400 4950);
WIRE 16 -1 (600 4900)(400 4900);
WIRE 16 -1 (850 4850)(400 4850);
WIRE 16 -1 (600 4800)(400 4800);
WIRE 16 -1 (850 4750)(400 4750);
WIRE 16 -1 (600 4700)(400 4700);
WIRE 16 -1 (850 4650)(400 4650);
WIRE 16 -1 (600 4600)(400 4600);
WIRE 16 -1 (850 4550)(400 4550);
WIRE 16 -1 (600 4500)(400 4500);
WIRE 16 -1 (850 4450)(400 4450);
WIRE 16 -1 (600 5200)(400 5200);
WIRE 16 -1 (850 5150)(400 5150);
DOT 1 (1100 2950);
DOT 1 (1100 3000);
DOT 1 (-750 2750);
DOT 1 (-750 2800);
DOT 1 (-750 1750);
DOT 1 (-750 1800);
DOT 1 (-750 1350);
DOT 1 (2500 1750);
DOT 1 (2500 3550);
DOT 1 (1100 3550);
DOT 1 (2500 3500);
DOT 1 (1100 3500);
DOT 1 (2500 3450);
DOT 1 (2500 3400);
DOT 1 (2500 3350);
DOT 1 (2500 3300);
DOT 1 (2500 3250);
DOT 1 (2500 3200);
DOT 1 (2500 3150);
DOT 1 (2500 3100);
DOT 1 (2500 3050);
DOT 1 (2500 3000);
DOT 1 (2500 2950);
DOT 1 (2500 2900);
DOT 1 (2500 2850);
DOT 1 (2500 2800);
DOT 1 (2500 2750);
DOT 1 (2500 2700);
DOT 1 (2500 2650);
DOT 1 (2500 2600);
DOT 1 (2500 2550);
DOT 1 (2500 2500);
DOT 1 (2500 2450);
DOT 1 (2500 2400);
DOT 1 (2500 2350);
DOT 1 (2500 2300);
DOT 1 (2500 2250);
DOT 1 (2500 2200);
DOT 1 (2500 2150);
DOT 1 (2500 2100);
DOT 1 (2500 2050);
DOT 1 (2500 2000);
DOT 1 (2500 1950);
DOT 1 (2500 1900);
DOT 1 (2500 1850);
DOT 1 (2500 1800);
DOT 1 (2500 1700);
DOT 1 (2500 1650);
DOT 1 (2500 1600);
DOT 1 (2500 1550);
DOT 1 (2500 1500);
DOT 1 (2500 1450);
DOT 1 (2500 1400);
DOT 1 (2500 1350);
DOT 1 (2500 1300);
DOT 1 (1100 3400);
DOT 1 (1100 3450);
DOT 1 (1100 3350);
DOT 1 (1100 3300);
DOT 1 (1100 3250);
DOT 1 (1100 3150);
DOT 1 (1100 3100);
DOT 1 (1100 3050);
DOT 1 (1100 2900);
DOT 1 (1100 2850);
DOT 1 (1100 2800);
DOT 1 (1100 2750);
DOT 1 (1100 2650);
DOT 1 (1100 2700);
DOT 1 (1100 2500);
DOT 1 (1100 2600);
DOT 1 (1100 2550);
DOT 1 (1100 2450);
DOT 1 (1100 2400);
DOT 1 (1100 2350);
DOT 1 (1100 2250);
DOT 1 (1100 2300);
DOT 1 (1100 2200);
DOT 1 (1100 2150);
DOT 1 (1100 2100);
DOT 1 (1100 2050);
DOT 1 (1100 2000);
DOT 1 (1100 1950);
DOT 1 (1100 1900);
DOT 1 (1100 1850);
DOT 1 (1100 1750);
DOT 1 (1100 1800);
DOT 1 (1100 1700);
DOT 1 (1100 1650);
DOT 1 (1100 1600);
DOT 1 (1100 1550);
DOT 1 (1100 1500);
DOT 1 (1100 1450);
DOT 1 (1100 1350);
DOT 1 (1100 1400);
DOT 1 (1100 1300);
DOT 1 (-750 2350);
DOT 1 (-750 2300);
DOT 1 (-750 2250);
DOT 1 (-750 2200);
DOT 1 (-750 2150);
DOT 1 (-750 2100);
DOT 1 (-750 2050);
DOT 1 (-750 2000);
DOT 1 (-750 1950);
DOT 1 (-750 1850);
DOT 1 (-750 1900);
DOT 1 (-750 1700);
DOT 1 (-750 1600);
DOT 1 (-750 1550);
DOT 1 (-750 1500);
DOT 1 (-750 1450);
DOT 1 (-750 1400);
DOT 1 (-750 1300);
DOT 1 (-750 1200);
DOT 1 (-750 1250);
DOT 1 (-4650 2000);
DOT 1 (-750 2700);
DOT 1 (-750 1150);
DOT 1 (-750 2500);
DOT 1 (-750 2650);
DOT 1 (1100 3200);
DOT 1 (-3300 2250);
DOT 1 (-3300 2200);
DOT 1 (-750 1650);
DOT 1 (650 2800);
FORCENOTE
SMBUS ADDR: 0XA0
(-5308 693) 0;
DISPLAY LEFT (-5308 693);
DISPLAY 1.595745 (-5308 693);
PAINT PURPLE (-5308 693);
FORCENOTE
PLACE CAP NEAR DIMM CONNECTOR
(-5288 852) 0;
DISPLAY LEFT (-5288 852);
DISPLAY 1.595745 (-5288 852);
PAINT PURPLE (-5288 852);
QUIT
